FILE_TYPE = MACRO_DRAWING;
SET COLOR_WIRE YELLOW;
SET COLOR_PROP ORANGE;
SET COLOR_DOT WHITE;
SET COLOR_ARC YELLOW;
SET COLOR_BODY GREEN;
SET COLOR_NOTE PURPLE;
SET PROP_DISPLAY VALUE;
SET PAGE_NUMBER P145;
FORCEADD UNIVERSAL_GND..1
(-3525 7025);
FORCEPROP 3 LASTPIN (-3525 7075) SIG_NAME GND\g
J 0
(-3515 7085);
DISPLAY 0.659574 (-3515 7085);
PAINT MONO (-3515 7085);
DISPLAY INVISIBLE (-3515 7085);
FORCEPROP 2 LAST CDS_LIB logical_power
J 0
(-3525 7025);
DISPLAY INVISIBLE (-3525 7025);
FORCEPROP 1 LAST PATH I10
J 0
(-3450 7025);
DISPLAY 0.872340 (-3450 7025);
PAINT AQUA (-3450 7025);
DISPLAY INVISIBLE (-3450 7025);
FORCEPROP 1 LAST HDL_POWER GND
J 1
(-3500 6950);
DISPLAY 0.872340 (-3500 6950);
PAINT GREEN (-3500 6950);
DISPLAY INVISIBLE (-3500 6950);
FORCEADD MOSFET_NCH_DUAL..2
(1875 7800);
FORCEPROP 1 LAST PART_NUMBER BAM138K0003
J 0
(2026 7706);
DISPLAY 0.723404 (2026 7706);
PAINT GREEN (2026 7706);
DISPLAY INVISIBLE (2026 7706);
FORCEPROP 1 LAST MATERIAL IC
J 0
(2026 7651);
DISPLAY 0.723404 (2026 7651);
PAINT GREEN (2026 7651);
FORCEPROP 2 LAST VALUE PJT138K
J 0
(2050 7825);
DISPLAY 1.021277 (2050 7825);
FORCEPROP 2 LAST PART_TYPE SMLF
J 0
(2050 7875);
DISPLAY 1.021277 (2050 7875);
FORCEPROP 1 LAST LOCATION Q71
J 0
(2026 7776);
DISPLAY 0.723404 (2026 7776);
PAINT GREEN (2026 7776);
FORCEPROP 0 LASTPIN (1925 8000) $PN 3
R 1
J 0
(1915 8010);
DISPLAY 0.680851 (1915 8010);
PAINT MONO (1915 8010);
FORCEPROP 0 LASTPIN (1675 7750) $PN 5
J 2
(1665 7760);
DISPLAY 0.680851 (1665 7760);
PAINT MONO (1665 7760);
FORCEPROP 0 LASTPIN (1925 7600) $PN 4
R 1
J 2
(1915 7590);
DISPLAY 0.680851 (1915 7590);
PAINT MONO (1915 7590);
FORCEPROP 1 LAST CDS_LMAN_SYM_OUTLINE -150,150,150,-150
J 0
(1875 7800);
DISPLAY 0.468085 (1875 7800);
PAINT GREEN (1875 7800);
DISPLAY INVISIBLE (1875 7800);
FORCEPROP 1 LAST PATH I100
J 0
(2025 7650);
DISPLAY 0.723404 (2025 7650);
PAINT GREEN (2025 7650);
DISPLAY INVISIBLE (2025 7650);
FORCEPROP 1 LAST NEEDS_NO_SIZE TRUE
J 0
(2025 7691);
DISPLAY 0.468085 (2025 7691);
PAINT GREEN (2025 7691);
DISPLAY INVISIBLE (2025 7691);
FORCEPROP 2 LAST CDS_LIB pure_quanta
J 0
(1875 7800);
DISPLAY INVISIBLE (1875 7800);
FORCEPROP 0 LAST $SEC 2
J 0
(2050 7925);
DISPLAY 0.680851 (2050 7925);
PAINT MONO (2050 7925);
DISPLAY INVISIBLE (2050 7925);
FORCEPROP 0 LAST CDS_SEC 2
J 0
(2050 7925);
DISPLAY 1.021277 (2050 7925);
DISPLAY INVISIBLE (2050 7925);
FORCEADD Q_RES..2
(1925 8175);
FORCEPROP 1 LAST PART_NUMBER CS24702JB10
J 0
(1965 8000);
DISPLAY 0.638298 (1965 8000);
DISPLAY INVISIBLE (1965 8000);
FORCEPROP 1 LAST TOLERANCE 5%
J 0
(1970 8200);
DISPLAY 0.638298 (1970 8200);
FORCEPROP 1 LAST VALUE 4.7K
J 0
(1970 8250);
DISPLAY 0.638298 (1970 8250);
FORCEPROP 1 LAST MATERIAL CHIP
J 0
(1965 8100);
DISPLAY 0.638298 (1965 8100);
FORCEPROP 1 LAST WATTAGE 1/16W
J 0
(1965 8150);
DISPLAY 0.638298 (1965 8150);
FORCEPROP 1 LAST PACK_TYPE 0402LF
J 0
(1965 8050);
DISPLAY 0.638298 (1965 8050);
FORCEPROP 1 LAST $LOCATION R2934
J 0
(1970 8300);
DISPLAY 0.978723 (1970 8300);
FORCEPROP 1 LASTPIN (1925 8275) $PN 1
J 0
(1930 8237);
DISPLAY 0.787234 (1930 8237);
PAINT MONO (1930 8237);
FORCEPROP 1 LASTPIN (1925 8075) $PN 2
J 0
(1930 8085);
DISPLAY 0.787234 (1930 8085);
PAINT MONO (1930 8085);
FORCEPROP 2 LAST CDS_LIB pure_quanta
J 0
(1925 8175);
DISPLAY INVISIBLE (1925 8175);
FORCEPROP 1 LAST PATH I101
J 0
(1975 8350);
DISPLAY 0.978723 (1975 8350);
PAINT WHITE (1975 8350);
DISPLAY INVISIBLE (1975 8350);
FORCEPROP 0 LAST CDS_LOCATION R2934
J 0
(1975 8350);
DISPLAY 1.021277 (1975 8350);
DISPLAY INVISIBLE (1975 8350);
FORCEPROP 0 LAST $SEC 1
J 0
(1975 8350);
DISPLAY 0.680851 (1975 8350);
PAINT MONO (1975 8350);
DISPLAY INVISIBLE (1975 8350);
FORCEPROP 0 LAST CDS_SEC 1
J 0
(1975 8350);
DISPLAY 1.021277 (1975 8350);
DISPLAY INVISIBLE (1975 8350);
FORCEADD UNIVERSAL_POWER..1
(1925 8475);
FORCEPROP 3 LASTPIN (1925 8425) SIG_NAME P3V3_AUX\g
J 0
(1935 8435);
DISPLAY 0.659574 (1935 8435);
PAINT MONO (1935 8435);
DISPLAY INVISIBLE (1935 8435);
FORCEPROP 1 LAST HDL_POWER P3V3_AUX
J 1
(1925 8525);
DISPLAY 0.872340 (1925 8525);
PAINT GREEN (1925 8525);
FORCEPROP 2 LAST CDS_LIB logical_power
J 0
(1925 8475);
DISPLAY INVISIBLE (1925 8475);
FORCEPROP 1 LAST PATH I102
J 0
(1975 8500);
DISPLAY 0.872340 (1975 8500);
PAINT AQUA (1975 8500);
DISPLAY INVISIBLE (1975 8500);
FORCEADD UNIVERSAL_GND..1
(1925 7425);
FORCEPROP 3 LASTPIN (1925 7475) SIG_NAME GND\g
J 0
(1935 7485);
DISPLAY 0.659574 (1935 7485);
PAINT MONO (1935 7485);
DISPLAY INVISIBLE (1935 7485);
FORCEPROP 2 LAST CDS_LIB logical_power
J 0
(1925 7425);
DISPLAY INVISIBLE (1925 7425);
FORCEPROP 1 LAST PATH I103
J 0
(2000 7425);
DISPLAY 0.872340 (2000 7425);
PAINT AQUA (2000 7425);
DISPLAY INVISIBLE (2000 7425);
FORCEPROP 1 LAST HDL_POWER GND
J 1
(1950 7350);
DISPLAY 0.872340 (1950 7350);
PAINT GREEN (1950 7350);
DISPLAY INVISIBLE (1950 7350);
FORCEADD UNIVERSAL_GND..1
(2925 6050);
FORCEPROP 3 LASTPIN (2925 6100) SIG_NAME GND\g
J 0
(2935 6110);
DISPLAY 0.659574 (2935 6110);
PAINT MONO (2935 6110);
DISPLAY INVISIBLE (2935 6110);
FORCEPROP 1 LAST PATH I104
J 0
(3000 6050);
DISPLAY 0.872340 (3000 6050);
PAINT AQUA (3000 6050);
DISPLAY INVISIBLE (3000 6050);
FORCEPROP 1 LAST HDL_POWER GND
J 1
(2950 5975);
DISPLAY 0.872340 (2950 5975);
PAINT GREEN (2950 5975);
DISPLAY INVISIBLE (2950 5975);
FORCEPROP 2 LAST CDS_LIB logical_power
J 0
(2925 6050);
DISPLAY INVISIBLE (2925 6050);
FORCEADD Q_CAP..1
(2925 6250);
FORCEPROP 1 LAST PART_NUMBER TMP_QCH21006JB10
J 0
(2975 6100);
DISPLAY 0.638298 (2975 6100);
DISPLAY INVISIBLE (2975 6100);
FORCEPROP 1 LAST VALUE 1000PF
J 0
(2975 6300);
DISPLAY 0.638298 (2975 6300);
FORCEPROP 1 LAST MATERIAL EMPTY
J 0
(2975 6150);
DISPLAY 0.638298 (2975 6150);
PAINT RED (2975 6150);
FORCEPROP 1 LAST TOLERANCE 5%
J 0
(2975 6200);
DISPLAY 0.638298 (2975 6200);
FORCEPROP 1 LAST PACK_TYPE 0402
J 0
(2975 6050);
DISPLAY 0.638298 (2975 6050);
FORCEPROP 1 LAST VOLTAGE 50V
J 0
(2975 6250);
DISPLAY 0.638298 (2975 6250);
FORCEPROP 1 LAST $LOCATION C1756
J 0
(2975 6350);
DISPLAY 0.638298 (2975 6350);
FORCEPROP 1 LASTPIN (2925 6350) $PN 1
J 0
(2935 6330);
DISPLAY 0.787234 (2935 6330);
PAINT MONO (2935 6330);
FORCEPROP 1 LASTPIN (2925 6150) $PN 2
J 0
(2935 6130);
DISPLAY 0.787234 (2935 6130);
PAINT MONO (2935 6130);
FORCEPROP 1 LAST PATH I105
J 0
(2975 6400);
DISPLAY 0.978723 (2975 6400);
PAINT WHITE (2975 6400);
DISPLAY INVISIBLE (2975 6400);
FORCEPROP 2 LAST CDS_LIB pure_quanta
J 0
(2925 6250);
DISPLAY INVISIBLE (2925 6250);
FORCEPROP 2 LAST CDS_LOCATION C1756
J 0
(2975 6450);
DISPLAY 1.021277 (2975 6450);
DISPLAY INVISIBLE (2975 6450);
FORCEPROP 2 LAST $SEC 1
J 0
(2975 6450);
DISPLAY 0.680851 (2975 6450);
PAINT MONO (2975 6450);
DISPLAY INVISIBLE (2975 6450);
FORCEPROP 2 LAST CDS_SEC 1
J 0
(2975 6450);
DISPLAY 1.021277 (2975 6450);
DISPLAY INVISIBLE (2975 6450);
FORCEADD OFFPAGE..2
(3200 6650);
FORCEPROP 2 LAST $XR0 213 
J 0
(3389 6650);
DISPLAY 0.638298 (3389 6650);
PAINT MONO (3389 6650);
FORCEPROP 2 LAST PATH I106
J 0
(3400 6700);
DISPLAY 1.021277 (3400 6700);
DISPLAY INVISIBLE (3400 6700);
FORCEPROP 2 LAST CDS_LIB standard
J 0
(3200 6650);
DISPLAY INVISIBLE (3200 6650);
FORCEPROP 1 LAST OFFPAGE TRUE
J 0
(3525 6525);
DISPLAY 0.872340 (3525 6525);
PAINT AQUA (3525 6525);
DISPLAY INVISIBLE (3525 6525);
FORCEPROP 1 LAST COMMENT_BODY TRUE
J 0
(3155 6555);
DISPLAY 0.872340 (3155 6555);
PAINT GREEN (3155 6555);
DISPLAY INVISIBLE (3155 6555);
FORCEADD UNIVERSAL_GND..1
(2025 6050);
FORCEPROP 3 LASTPIN (2025 6100) SIG_NAME GND\g
J 0
(2035 6110);
DISPLAY 0.659574 (2035 6110);
PAINT MONO (2035 6110);
DISPLAY INVISIBLE (2035 6110);
FORCEPROP 1 LAST PATH I108
J 0
(2100 6050);
DISPLAY 0.872340 (2100 6050);
PAINT AQUA (2100 6050);
DISPLAY INVISIBLE (2100 6050);
FORCEPROP 1 LAST HDL_POWER GND
J 1
(2050 5975);
DISPLAY 0.872340 (2050 5975);
PAINT GREEN (2050 5975);
DISPLAY INVISIBLE (2050 5975);
FORCEPROP 2 LAST CDS_LIB logical_power
J 0
(2025 6050);
DISPLAY INVISIBLE (2025 6050);
FORCEADD Q_RES..2
(2025 6875);
FORCEPROP 1 LAST PART_NUMBER CS24702JB10
J 0
(2065 6700);
DISPLAY 0.638298 (2065 6700);
DISPLAY INVISIBLE (2065 6700);
FORCEPROP 1 LAST VALUE 4.7K
J 0
(2070 6950);
DISPLAY 0.638298 (2070 6950);
FORCEPROP 1 LAST TOLERANCE 5%
J 0
(2070 6900);
DISPLAY 0.638298 (2070 6900);
FORCEPROP 1 LAST MATERIAL CHIP
J 0
(2065 6800);
DISPLAY 0.638298 (2065 6800);
FORCEPROP 1 LAST WATTAGE 1/16W
J 0
(2065 6850);
DISPLAY 0.638298 (2065 6850);
FORCEPROP 1 LAST PACK_TYPE 0402LF
J 0
(2065 6750);
DISPLAY 0.638298 (2065 6750);
FORCEPROP 1 LAST $LOCATION R2935
J 0
(2070 7000);
DISPLAY 0.978723 (2070 7000);
FORCEPROP 1 LASTPIN (2025 6975) $PN 1
J 0
(2030 6937);
DISPLAY 0.787234 (2030 6937);
PAINT MONO (2030 6937);
FORCEPROP 1 LASTPIN (2025 6775) $PN 2
J 0
(2030 6785);
DISPLAY 0.787234 (2030 6785);
PAINT MONO (2030 6785);
FORCEPROP 1 LAST PATH I109
J 0
(2075 7050);
DISPLAY 0.978723 (2075 7050);
PAINT WHITE (2075 7050);
DISPLAY INVISIBLE (2075 7050);
FORCEPROP 2 LAST CDS_LIB pure_quanta
J 0
(2025 6875);
DISPLAY INVISIBLE (2025 6875);
FORCEPROP 0 LAST CDS_LOCATION R2935
J 0
(2075 7050);
DISPLAY 1.021277 (2075 7050);
DISPLAY INVISIBLE (2075 7050);
FORCEPROP 0 LAST $SEC 1
J 0
(2075 7050);
DISPLAY 0.680851 (2075 7050);
PAINT MONO (2075 7050);
DISPLAY INVISIBLE (2075 7050);
FORCEPROP 0 LAST CDS_SEC 1
J 0
(2075 7050);
DISPLAY 1.021277 (2075 7050);
DISPLAY INVISIBLE (2075 7050);
FORCEADD UNIVERSAL_GND..1
(-3475 5625);
FORCEPROP 3 LASTPIN (-3475 5675) SIG_NAME GND\g
J 0
(-3465 5685);
DISPLAY 0.659574 (-3465 5685);
PAINT MONO (-3465 5685);
DISPLAY INVISIBLE (-3465 5685);
FORCEPROP 1 LAST HDL_POWER GND
J 1
(-3450 5550);
DISPLAY 0.872340 (-3450 5550);
PAINT GREEN (-3450 5550);
DISPLAY INVISIBLE (-3450 5550);
FORCEPROP 1 LAST PATH I11
J 0
(-3400 5625);
DISPLAY 0.872340 (-3400 5625);
PAINT AQUA (-3400 5625);
DISPLAY INVISIBLE (-3400 5625);
FORCEPROP 2 LAST CDS_LIB logical_power
J 0
(-3475 5625);
DISPLAY INVISIBLE (-3475 5625);
FORCEADD UNIVERSAL_POWER..1
(2025 7175);
FORCEPROP 3 LASTPIN (2025 7125) SIG_NAME P3V3_AUX\g
J 0
(2035 7135);
DISPLAY 0.659574 (2035 7135);
PAINT MONO (2035 7135);
DISPLAY INVISIBLE (2035 7135);
FORCEPROP 1 LAST HDL_POWER P3V3_AUX
J 1
(2025 7225);
DISPLAY 0.872340 (2025 7225);
PAINT GREEN (2025 7225);
FORCEPROP 1 LAST PATH I110
J 0
(2075 7200);
DISPLAY 0.872340 (2075 7200);
PAINT AQUA (2075 7200);
DISPLAY INVISIBLE (2075 7200);
FORCEPROP 2 LAST CDS_LIB logical_power
J 0
(2025 7175);
DISPLAY INVISIBLE (2025 7175);
FORCEADD Q_CAP..1
(2875 7775);
FORCEPROP 1 LAST PART_NUMBER TMP_QCH21006JB10
J 0
(2925 7625);
DISPLAY 0.638298 (2925 7625);
DISPLAY INVISIBLE (2925 7625);
FORCEPROP 1 LAST MATERIAL EMPTY
J 0
(2925 7675);
DISPLAY 0.638298 (2925 7675);
PAINT RED (2925 7675);
FORCEPROP 1 LAST VALUE 1000PF
J 0
(2925 7825);
DISPLAY 0.638298 (2925 7825);
FORCEPROP 1 LAST VOLTAGE 50V
J 0
(2925 7775);
DISPLAY 0.638298 (2925 7775);
FORCEPROP 1 LAST TOLERANCE 5%
J 0
(2925 7725);
DISPLAY 0.638298 (2925 7725);
FORCEPROP 1 LAST PACK_TYPE 0402
J 0
(2925 7575);
DISPLAY 0.638298 (2925 7575);
FORCEPROP 1 LAST $LOCATION C1774
J 0
(2925 7875);
DISPLAY 0.978723 (2925 7875);
FORCEPROP 1 LASTPIN (2875 7875) $PN 1
J 0
(2885 7855);
DISPLAY 0.787234 (2885 7855);
PAINT MONO (2885 7855);
FORCEPROP 1 LASTPIN (2875 7675) $PN 2
J 0
(2885 7655);
DISPLAY 0.787234 (2885 7655);
PAINT MONO (2885 7655);
FORCEPROP 2 LAST CDS_LIB pure_quanta
J 0
(2875 7775);
DISPLAY INVISIBLE (2875 7775);
FORCEPROP 1 LAST PATH I111
J 0
(2925 7925);
DISPLAY 0.978723 (2925 7925);
PAINT WHITE (2925 7925);
DISPLAY INVISIBLE (2925 7925);
FORCEPROP 0 LAST CDS_LOCATION C1774
J 0
(2925 7925);
DISPLAY 1.021277 (2925 7925);
DISPLAY INVISIBLE (2925 7925);
FORCEPROP 0 LAST $SEC 1
J 0
(2925 7925);
DISPLAY 0.680851 (2925 7925);
PAINT MONO (2925 7925);
DISPLAY INVISIBLE (2925 7925);
FORCEPROP 0 LAST CDS_SEC 1
J 0
(2925 7925);
DISPLAY 1.021277 (2925 7925);
DISPLAY INVISIBLE (2925 7925);
FORCEADD UNIVERSAL_GND..1
(2875 7575);
FORCEPROP 3 LASTPIN (2875 7625) SIG_NAME GND\g
J 0
(2885 7635);
DISPLAY 0.659574 (2885 7635);
PAINT MONO (2885 7635);
DISPLAY INVISIBLE (2885 7635);
FORCEPROP 2 LAST CDS_LIB logical_power
J 0
(2875 7575);
DISPLAY INVISIBLE (2875 7575);
FORCEPROP 1 LAST PATH I112
J 0
(2950 7575);
DISPLAY 0.872340 (2950 7575);
PAINT AQUA (2950 7575);
DISPLAY INVISIBLE (2950 7575);
FORCEPROP 1 LAST HDL_POWER GND
J 1
(2900 7500);
DISPLAY 0.872340 (2900 7500);
PAINT GREEN (2900 7500);
DISPLAY INVISIBLE (2900 7500);
FORCEADD UNIVERSAL_GND..1
(-1600 7450);
FORCEPROP 3 LASTPIN (-1600 7500) SIG_NAME GND\g
J 0
(-1590 7510);
DISPLAY 0.659574 (-1590 7510);
PAINT MONO (-1590 7510);
DISPLAY INVISIBLE (-1590 7510);
FORCEPROP 1 LAST HDL_POWER GND
J 1
(-1575 7375);
DISPLAY 0.872340 (-1575 7375);
PAINT GREEN (-1575 7375);
DISPLAY INVISIBLE (-1575 7375);
FORCEPROP 1 LAST PATH I113
J 0
(-1525 7450);
DISPLAY 0.872340 (-1525 7450);
PAINT AQUA (-1525 7450);
DISPLAY INVISIBLE (-1525 7450);
FORCEPROP 2 LAST CDS_LIB logical_power
J 0
(-1600 7450);
DISPLAY INVISIBLE (-1600 7450);
FORCEADD Q_CAP..1
(-1600 7650);
FORCEPROP 1 LAST PART_NUMBER TMP_QCH21006JB10
J 0
(-1550 7500);
DISPLAY 0.638298 (-1550 7500);
DISPLAY INVISIBLE (-1550 7500);
FORCEPROP 1 LAST TOLERANCE 5%
J 0
(-1550 7600);
DISPLAY 0.638298 (-1550 7600);
FORCEPROP 1 LAST MATERIAL EMPTY
J 0
(-1550 7550);
DISPLAY 0.638298 (-1550 7550);
PAINT RED (-1550 7550);
FORCEPROP 1 LAST VOLTAGE 50V
J 0
(-1550 7650);
DISPLAY 0.638298 (-1550 7650);
FORCEPROP 1 LAST PACK_TYPE 0402
J 0
(-1550 7450);
DISPLAY 0.638298 (-1550 7450);
FORCEPROP 1 LAST VALUE 1000PF
J 0
(-1550 7700);
DISPLAY 0.638298 (-1550 7700);
FORCEPROP 1 LAST $LOCATION C1773
J 0
(-1550 7750);
DISPLAY 0.978723 (-1550 7750);
FORCEPROP 1 LASTPIN (-1600 7750) $PN 1
J 0
(-1590 7730);
DISPLAY 0.787234 (-1590 7730);
PAINT MONO (-1590 7730);
FORCEPROP 1 LASTPIN (-1600 7550) $PN 2
J 0
(-1590 7530);
DISPLAY 0.787234 (-1590 7530);
PAINT MONO (-1590 7530);
FORCEPROP 1 LAST PATH I114
J 0
(-1550 7800);
DISPLAY 0.978723 (-1550 7800);
PAINT WHITE (-1550 7800);
DISPLAY INVISIBLE (-1550 7800);
FORCEPROP 2 LAST CDS_LIB pure_quanta
J 0
(-1600 7650);
DISPLAY INVISIBLE (-1600 7650);
FORCEPROP 0 LAST CDS_LOCATION C1773
J 0
(-1550 7800);
DISPLAY 1.021277 (-1550 7800);
DISPLAY INVISIBLE (-1550 7800);
FORCEPROP 0 LAST $SEC 1
J 0
(-1550 7800);
DISPLAY 0.680851 (-1550 7800);
PAINT MONO (-1550 7800);
DISPLAY INVISIBLE (-1550 7800);
FORCEPROP 0 LAST CDS_SEC 1
J 0
(-1550 7800);
DISPLAY 1.021277 (-1550 7800);
DISPLAY INVISIBLE (-1550 7800);
FORCEADD UNIVERSAL_GND..1
(-1650 6075);
FORCEPROP 3 LASTPIN (-1650 6125) SIG_NAME GND\g
J 0
(-1640 6135);
DISPLAY 0.659574 (-1640 6135);
PAINT MONO (-1640 6135);
DISPLAY INVISIBLE (-1640 6135);
FORCEPROP 2 LAST CDS_LIB logical_power
J 0
(-1650 6075);
DISPLAY INVISIBLE (-1650 6075);
FORCEPROP 1 LAST PATH I115
J 0
(-1575 6075);
DISPLAY 0.872340 (-1575 6075);
PAINT AQUA (-1575 6075);
DISPLAY INVISIBLE (-1575 6075);
FORCEPROP 1 LAST HDL_POWER GND
J 1
(-1625 6000);
DISPLAY 0.872340 (-1625 6000);
PAINT GREEN (-1625 6000);
DISPLAY INVISIBLE (-1625 6000);
FORCEADD Q_CAP..1
(-1650 6275);
FORCEPROP 1 LAST PART_NUMBER TMP_QCH21006JB10
J 0
(-1600 6125);
DISPLAY 0.638298 (-1600 6125);
DISPLAY INVISIBLE (-1600 6125);
FORCEPROP 1 LAST VALUE 1000PF
J 0
(-1600 6325);
DISPLAY 0.638298 (-1600 6325);
FORCEPROP 1 LAST MATERIAL EMPTY
J 0
(-1600 6175);
DISPLAY 0.638298 (-1600 6175);
PAINT RED (-1600 6175);
FORCEPROP 1 LAST PACK_TYPE 0402
J 0
(-1600 6075);
DISPLAY 0.638298 (-1600 6075);
FORCEPROP 1 LAST VOLTAGE 50V
J 0
(-1600 6275);
DISPLAY 0.638298 (-1600 6275);
FORCEPROP 1 LAST TOLERANCE 5%
J 0
(-1600 6225);
DISPLAY 0.638298 (-1600 6225);
FORCEPROP 1 LAST $LOCATION C1772
J 0
(-1600 6375);
DISPLAY 0.978723 (-1600 6375);
FORCEPROP 1 LASTPIN (-1650 6375) $PN 1
J 0
(-1640 6355);
DISPLAY 0.787234 (-1640 6355);
PAINT MONO (-1640 6355);
FORCEPROP 1 LASTPIN (-1650 6175) $PN 2
J 0
(-1640 6155);
DISPLAY 0.787234 (-1640 6155);
PAINT MONO (-1640 6155);
FORCEPROP 2 LAST CDS_LIB pure_quanta
J 0
(-1650 6275);
DISPLAY INVISIBLE (-1650 6275);
FORCEPROP 1 LAST PATH I116
J 0
(-1600 6425);
DISPLAY 0.978723 (-1600 6425);
PAINT WHITE (-1600 6425);
DISPLAY INVISIBLE (-1600 6425);
FORCEPROP 0 LAST CDS_LOCATION C1772
J 0
(-1600 6425);
DISPLAY 1.021277 (-1600 6425);
DISPLAY INVISIBLE (-1600 6425);
FORCEPROP 0 LAST $SEC 1
J 0
(-1600 6425);
DISPLAY 0.680851 (-1600 6425);
PAINT MONO (-1600 6425);
DISPLAY INVISIBLE (-1600 6425);
FORCEPROP 0 LAST CDS_SEC 1
J 0
(-1600 6425);
DISPLAY 1.021277 (-1600 6425);
DISPLAY INVISIBLE (-1600 6425);
FORCEADD MOSFET_NCH_DUAL..1
(-3525 6000);
FORCEPROP 1 LAST PART_NUMBER BAM138K0003
J 0
(-3374 5914);
DISPLAY 0.723404 (-3374 5914);
PAINT GREEN (-3374 5914);
DISPLAY INVISIBLE (-3374 5914);
FORCEPROP 2 LAST VALUE PJT138K
J 0
(-3350 6025);
DISPLAY 1.021277 (-3350 6025);
FORCEPROP 1 LAST MATERIAL IC
J 0
(-3374 5849);
DISPLAY 0.723404 (-3374 5849);
PAINT GREEN (-3374 5849);
FORCEPROP 2 LAST PART_TYPE SMLF
J 0
(-3350 6075);
DISPLAY 1.021277 (-3350 6075);
FORCEPROP 1 LAST LOCATION Q69
J 0
(-3374 5974);
DISPLAY 0.723404 (-3374 5974);
PAINT GREEN (-3374 5974);
FORCEPROP 0 LASTPIN (-3475 6200) $PN 6
R 1
J 0
(-3485 6210);
DISPLAY 0.680851 (-3485 6210);
PAINT MONO (-3485 6210);
FORCEPROP 0 LASTPIN (-3725 5950) $PN 2
J 2
(-3735 5960);
DISPLAY 0.680851 (-3735 5960);
PAINT MONO (-3735 5960);
FORCEPROP 0 LASTPIN (-3475 5800) $PN 1
R 1
J 2
(-3485 5790);
DISPLAY 0.680851 (-3485 5790);
PAINT MONO (-3485 5790);
FORCEPROP 1 LAST CDS_LMAN_SYM_OUTLINE -150,150,150,-150
J 0
(-3525 6000);
DISPLAY 0.468085 (-3525 6000);
PAINT GREEN (-3525 6000);
DISPLAY INVISIBLE (-3525 6000);
FORCEPROP 1 LAST PATH I117
J 0
(-3525 6000);
DISPLAY 0.723404 (-3525 6000);
PAINT GREEN (-3525 6000);
DISPLAY INVISIBLE (-3525 6000);
FORCEPROP 1 LAST NEEDS_NO_SIZE TRUE
J 0
(-3525 5999);
DISPLAY 0.468085 (-3525 5999);
PAINT GREEN (-3525 5999);
DISPLAY INVISIBLE (-3525 5999);
FORCEPROP 2 LAST CDS_LIB pure_quanta
J 0
(-3525 6000);
DISPLAY INVISIBLE (-3525 6000);
FORCEPROP 0 LAST $SEC 1
J 0
(-3350 6125);
DISPLAY 0.680851 (-3350 6125);
PAINT MONO (-3350 6125);
DISPLAY INVISIBLE (-3350 6125);
FORCEPROP 0 LAST CDS_SEC 1
J 0
(-3350 6125);
DISPLAY 1.021277 (-3350 6125);
DISPLAY INVISIBLE (-3350 6125);
FORCEADD MOSFET_NCH_DUAL..1
(1050 7525);
FORCEPROP 1 LAST PART_NUMBER BAM138K0003
J 0
(1201 7439);
DISPLAY 0.723404 (1201 7439);
PAINT GREEN (1201 7439);
DISPLAY INVISIBLE (1201 7439);
FORCEPROP 1 LAST MATERIAL IC
J 0
(1201 7374);
DISPLAY 0.723404 (1201 7374);
PAINT GREEN (1201 7374);
FORCEPROP 2 LAST PART_TYPE SMLF
J 0
(1225 7600);
DISPLAY 1.021277 (1225 7600);
FORCEPROP 2 LAST VALUE PJT138K
J 0
(1225 7550);
DISPLAY 1.021277 (1225 7550);
FORCEPROP 1 LAST LOCATION Q71
J 0
(1201 7499);
DISPLAY 0.723404 (1201 7499);
PAINT GREEN (1201 7499);
FORCEPROP 0 LASTPIN (1100 7725) $PN 6
R 1
J 0
(1090 7735);
DISPLAY 0.680851 (1090 7735);
PAINT MONO (1090 7735);
FORCEPROP 0 LASTPIN (850 7475) $PN 2
J 2
(840 7485);
DISPLAY 0.680851 (840 7485);
PAINT MONO (840 7485);
FORCEPROP 0 LASTPIN (1100 7325) $PN 1
R 1
J 2
(1090 7315);
DISPLAY 0.680851 (1090 7315);
PAINT MONO (1090 7315);
FORCEPROP 1 LAST CDS_LMAN_SYM_OUTLINE -150,150,150,-150
J 0
(1050 7525);
DISPLAY 0.468085 (1050 7525);
PAINT GREEN (1050 7525);
DISPLAY INVISIBLE (1050 7525);
FORCEPROP 1 LAST PATH I118
J 0
(1050 7525);
DISPLAY 0.723404 (1050 7525);
PAINT GREEN (1050 7525);
DISPLAY INVISIBLE (1050 7525);
FORCEPROP 1 LAST NEEDS_NO_SIZE TRUE
J 0
(1050 7524);
DISPLAY 0.468085 (1050 7524);
PAINT GREEN (1050 7524);
DISPLAY INVISIBLE (1050 7524);
FORCEPROP 2 LAST CDS_LIB pure_quanta
J 0
(1050 7525);
DISPLAY INVISIBLE (1050 7525);
FORCEPROP 0 LAST $SEC 1
J 0
(1225 7650);
DISPLAY 0.680851 (1225 7650);
PAINT MONO (1225 7650);
DISPLAY INVISIBLE (1225 7650);
FORCEPROP 0 LAST CDS_SEC 1
J 0
(1225 7650);
DISPLAY 1.021277 (1225 7650);
DISPLAY INVISIBLE (1225 7650);
FORCEADD MOSFET_NCH_DUAL..2
(1975 6425);
FORCEPROP 1 LAST PART_NUMBER BAM138K0003
J 0
(2126 6331);
DISPLAY 0.723404 (2126 6331);
PAINT GREEN (2126 6331);
DISPLAY INVISIBLE (2126 6331);
FORCEPROP 1 LAST MATERIAL IC
J 0
(2126 6276);
DISPLAY 0.723404 (2126 6276);
PAINT GREEN (2126 6276);
FORCEPROP 2 LAST VALUE PJT138K
J 0
(2150 6450);
DISPLAY 1.021277 (2150 6450);
FORCEPROP 2 LAST PART_TYPE SMLF
J 0
(2150 6500);
DISPLAY 1.021277 (2150 6500);
FORCEPROP 1 LAST LOCATION Q72
J 0
(2126 6401);
DISPLAY 0.723404 (2126 6401);
PAINT GREEN (2126 6401);
FORCEPROP 2 LASTPIN (2025 6625) $PN 3
R 1
J 0
(2015 6635);
DISPLAY 0.680851 (2015 6635);
PAINT MONO (2015 6635);
FORCEPROP 2 LASTPIN (1775 6375) $PN 5
J 2
(1765 6385);
DISPLAY 0.680851 (1765 6385);
PAINT MONO (1765 6385);
FORCEPROP 2 LASTPIN (2025 6225) $PN 4
R 1
J 2
(2015 6215);
DISPLAY 0.680851 (2015 6215);
PAINT MONO (2015 6215);
FORCEPROP 1 LAST CDS_LMAN_SYM_OUTLINE -150,150,150,-150
J 0
(1975 6425);
DISPLAY 0.468085 (1975 6425);
PAINT GREEN (1975 6425);
DISPLAY INVISIBLE (1975 6425);
FORCEPROP 1 LAST PATH I119
J 0
(2125 6275);
DISPLAY 0.723404 (2125 6275);
PAINT GREEN (2125 6275);
DISPLAY INVISIBLE (2125 6275);
FORCEPROP 1 LAST NEEDS_NO_SIZE TRUE
J 0
(2125 6316);
DISPLAY 0.468085 (2125 6316);
PAINT GREEN (2125 6316);
DISPLAY INVISIBLE (2125 6316);
FORCEPROP 2 LAST CDS_LIB pure_quanta
J 0
(1975 6425);
DISPLAY INVISIBLE (1975 6425);
FORCEPROP 2 LAST SEC_TYPE 
J 0
(2150 6550);
DISPLAY 1.021277 (2150 6550);
DISPLAY INVISIBLE (2150 6550);
FORCEPROP 2 LAST SEC 2
J 0
(2150 6550);
DISPLAY 0.680851 (2150 6550);
PAINT MONO (2150 6550);
DISPLAY INVISIBLE (2150 6550);
FORCEADD UNIVERSAL_GND..1
(-3450 4275);
FORCEPROP 3 LASTPIN (-3450 4325) SIG_NAME GND\g
J 0
(-3440 4335);
DISPLAY 0.659574 (-3440 4335);
PAINT MONO (-3440 4335);
DISPLAY INVISIBLE (-3440 4335);
FORCEPROP 1 LAST HDL_POWER GND
J 1
(-3425 4200);
DISPLAY 0.872340 (-3425 4200);
PAINT GREEN (-3425 4200);
DISPLAY INVISIBLE (-3425 4200);
FORCEPROP 2 LAST CDS_LIB logical_power
J 0
(-3450 4275);
DISPLAY INVISIBLE (-3450 4275);
FORCEPROP 1 LAST PATH I12
J 0
(-3375 4275);
DISPLAY 0.872340 (-3375 4275);
PAINT AQUA (-3375 4275);
DISPLAY INVISIBLE (-3375 4275);
FORCEADD MOSFET_NCH_DUAL..2
(-2550 4925);
FORCEPROP 1 LAST PART_NUMBER BAM138K0003
J 0
(-2399 4831);
DISPLAY 0.723404 (-2399 4831);
PAINT GREEN (-2399 4831);
DISPLAY INVISIBLE (-2399 4831);
FORCEPROP 2 LAST VALUE PJT138K
J 0
(-2375 4950);
DISPLAY 1.021277 (-2375 4950);
FORCEPROP 2 LAST PART_TYPE SMLF
J 0
(-2375 5000);
DISPLAY 1.021277 (-2375 5000);
FORCEPROP 1 LAST MATERIAL IC
J 0
(-2399 4776);
DISPLAY 0.723404 (-2399 4776);
PAINT GREEN (-2399 4776);
FORCEPROP 1 LAST LOCATION Q70
J 0
(-2399 4901);
DISPLAY 0.723404 (-2399 4901);
PAINT GREEN (-2399 4901);
FORCEPROP 0 LASTPIN (-2500 5125) $PN 3
R 1
J 0
(-2510 5135);
DISPLAY 0.680851 (-2510 5135);
PAINT MONO (-2510 5135);
FORCEPROP 0 LASTPIN (-2750 4875) $PN 5
J 2
(-2760 4885);
DISPLAY 0.680851 (-2760 4885);
PAINT MONO (-2760 4885);
FORCEPROP 0 LASTPIN (-2500 4725) $PN 4
R 1
J 2
(-2510 4715);
DISPLAY 0.680851 (-2510 4715);
PAINT MONO (-2510 4715);
FORCEPROP 1 LAST CDS_LMAN_SYM_OUTLINE -150,150,150,-150
J 0
(-2550 4925);
DISPLAY 0.468085 (-2550 4925);
PAINT GREEN (-2550 4925);
DISPLAY INVISIBLE (-2550 4925);
FORCEPROP 1 LAST PATH I120
J 0
(-2400 4775);
DISPLAY 0.723404 (-2400 4775);
PAINT GREEN (-2400 4775);
DISPLAY INVISIBLE (-2400 4775);
FORCEPROP 1 LAST NEEDS_NO_SIZE TRUE
J 0
(-2400 4816);
DISPLAY 0.468085 (-2400 4816);
PAINT GREEN (-2400 4816);
DISPLAY INVISIBLE (-2400 4816);
FORCEPROP 2 LAST CDS_LIB pure_quanta
J 0
(-2550 4925);
DISPLAY INVISIBLE (-2550 4925);
FORCEPROP 0 LAST $SEC 2
J 0
(-2375 5050);
DISPLAY 0.680851 (-2375 5050);
PAINT MONO (-2375 5050);
DISPLAY INVISIBLE (-2375 5050);
FORCEPROP 0 LAST CDS_SEC 2
J 0
(-2375 5050);
DISPLAY 1.021277 (-2375 5050);
DISPLAY INVISIBLE (-2375 5050);
FORCEADD MOSFET_NCH_DUAL..1
(1075 4775);
FORCEPROP 1 LAST PART_NUMBER BAM138K0003
J 0
(1226 4689);
DISPLAY 0.723404 (1226 4689);
PAINT GREEN (1226 4689);
DISPLAY INVISIBLE (1226 4689);
FORCEPROP 1 LAST MATERIAL IC
J 0
(1226 4624);
DISPLAY 0.723404 (1226 4624);
PAINT GREEN (1226 4624);
FORCEPROP 2 LAST PART_TYPE SMLF
J 0
(1250 4850);
DISPLAY 1.021277 (1250 4850);
FORCEPROP 2 LAST VALUE PJT138K
J 0
(1250 4800);
DISPLAY 1.021277 (1250 4800);
FORCEPROP 1 LAST LOCATION Q74
J 0
(1226 4749);
DISPLAY 0.723404 (1226 4749);
PAINT GREEN (1226 4749);
FORCEPROP 2 LASTPIN (1125 4975) $PN 6
R 1
J 0
(1115 4985);
DISPLAY 0.680851 (1115 4985);
PAINT MONO (1115 4985);
FORCEPROP 2 LASTPIN (875 4725) $PN 2
J 2
(865 4735);
DISPLAY 0.680851 (865 4735);
PAINT MONO (865 4735);
FORCEPROP 2 LASTPIN (1125 4575) $PN 1
R 1
J 2
(1115 4565);
DISPLAY 0.680851 (1115 4565);
PAINT MONO (1115 4565);
FORCEPROP 1 LAST CDS_LMAN_SYM_OUTLINE -150,150,150,-150
J 0
(1075 4775);
DISPLAY 0.468085 (1075 4775);
PAINT GREEN (1075 4775);
DISPLAY INVISIBLE (1075 4775);
FORCEPROP 1 LAST PATH I121
J 0
(1075 4775);
DISPLAY 0.723404 (1075 4775);
PAINT GREEN (1075 4775);
DISPLAY INVISIBLE (1075 4775);
FORCEPROP 1 LAST NEEDS_NO_SIZE TRUE
J 0
(1075 4774);
DISPLAY 0.468085 (1075 4774);
PAINT GREEN (1075 4774);
DISPLAY INVISIBLE (1075 4774);
FORCEPROP 2 LAST CDS_LIB pure_quanta
J 0
(1075 4775);
DISPLAY INVISIBLE (1075 4775);
FORCEPROP 2 LAST SEC_TYPE 
J 0
(1250 4900);
DISPLAY 1.021277 (1250 4900);
DISPLAY INVISIBLE (1250 4900);
FORCEPROP 2 LAST SEC 1
J 0
(1250 4900);
DISPLAY 0.680851 (1250 4900);
PAINT MONO (1250 4900);
DISPLAY INVISIBLE (1250 4900);
FORCEADD MOSFET_NCH_DUAL..2
(2000 5050);
FORCEPROP 1 LAST PART_NUMBER BAM138K0003
J 0
(2151 4956);
DISPLAY 0.723404 (2151 4956);
PAINT GREEN (2151 4956);
DISPLAY INVISIBLE (2151 4956);
FORCEPROP 1 LAST MATERIAL IC
J 0
(2151 4901);
DISPLAY 0.723404 (2151 4901);
PAINT GREEN (2151 4901);
FORCEPROP 2 LAST VALUE PJT138K
J 0
(2175 5075);
DISPLAY 1.021277 (2175 5075);
FORCEPROP 2 LAST PART_TYPE SMLF
J 0
(2175 5125);
DISPLAY 1.021277 (2175 5125);
FORCEPROP 1 LAST LOCATION Q74
J 0
(2151 5026);
DISPLAY 0.723404 (2151 5026);
PAINT GREEN (2151 5026);
FORCEPROP 2 LASTPIN (2050 5250) $PN 3
R 1
J 0
(2040 5260);
DISPLAY 0.680851 (2040 5260);
PAINT MONO (2040 5260);
FORCEPROP 2 LASTPIN (1800 5000) $PN 5
J 2
(1790 5010);
DISPLAY 0.680851 (1790 5010);
PAINT MONO (1790 5010);
FORCEPROP 2 LASTPIN (2050 4850) $PN 4
R 1
J 2
(2040 4840);
DISPLAY 0.680851 (2040 4840);
PAINT MONO (2040 4840);
FORCEPROP 1 LAST NEEDS_NO_SIZE TRUE
J 0
(2150 4941);
DISPLAY 0.468085 (2150 4941);
PAINT GREEN (2150 4941);
DISPLAY INVISIBLE (2150 4941);
FORCEPROP 1 LAST PATH I122
J 0
(2150 4900);
DISPLAY 0.723404 (2150 4900);
PAINT GREEN (2150 4900);
DISPLAY INVISIBLE (2150 4900);
FORCEPROP 1 LAST CDS_LMAN_SYM_OUTLINE -150,150,150,-150
J 0
(2000 5050);
DISPLAY 0.468085 (2000 5050);
PAINT GREEN (2000 5050);
DISPLAY INVISIBLE (2000 5050);
FORCEPROP 2 LAST CDS_LIB pure_quanta
J 0
(2000 5050);
DISPLAY INVISIBLE (2000 5050);
FORCEPROP 2 LAST SEC_TYPE 
J 0
(2175 5175);
DISPLAY 1.021277 (2175 5175);
DISPLAY INVISIBLE (2175 5175);
FORCEPROP 2 LAST SEC 2
J 0
(2175 5175);
DISPLAY 0.680851 (2175 5175);
PAINT MONO (2175 5175);
DISPLAY INVISIBLE (2175 5175);
FORCEADD UNIVERSAL_POWER..1
(2050 5800);
FORCEPROP 3 LASTPIN (2050 5750) SIG_NAME P3V3_AUX\g
J 0
(2060 5760);
DISPLAY 0.659574 (2060 5760);
PAINT MONO (2060 5760);
DISPLAY INVISIBLE (2060 5760);
FORCEPROP 1 LAST HDL_POWER P3V3_AUX
J 1
(2050 5850);
DISPLAY 0.872340 (2050 5850);
PAINT GREEN (2050 5850);
FORCEPROP 2 LAST CDS_LIB logical_power
J 0
(2050 5800);
DISPLAY INVISIBLE (2050 5800);
FORCEPROP 1 LAST PATH I123
J 0
(2100 5825);
DISPLAY 0.872340 (2100 5825);
PAINT AQUA (2100 5825);
DISPLAY INVISIBLE (2100 5825);
FORCEADD OFFPAGE..2
(3225 5275);
FORCEPROP 2 LAST $XR0 214 
J 0
(3414 5275);
DISPLAY 0.638298 (3414 5275);
PAINT MONO (3414 5275);
FORCEPROP 1 LAST COMMENT_BODY TRUE
J 0
(3180 5180);
DISPLAY 0.872340 (3180 5180);
PAINT GREEN (3180 5180);
DISPLAY INVISIBLE (3180 5180);
FORCEPROP 1 LAST OFFPAGE TRUE
J 0
(3550 5150);
DISPLAY 0.872340 (3550 5150);
PAINT AQUA (3550 5150);
DISPLAY INVISIBLE (3550 5150);
FORCEPROP 2 LAST CDS_LIB standard
J 0
(3225 5275);
DISPLAY INVISIBLE (3225 5275);
FORCEPROP 2 LAST PATH I124
J 0
(3425 5325);
DISPLAY 1.021277 (3425 5325);
DISPLAY INVISIBLE (3425 5325);
FORCEADD Q_CAP..1
(2950 4875);
FORCEPROP 1 LAST PART_NUMBER TMP_QCH21006JB10
J 0
(3000 4725);
DISPLAY 0.638298 (3000 4725);
DISPLAY INVISIBLE (3000 4725);
FORCEPROP 1 LAST TOLERANCE 5%
J 0
(3000 4825);
DISPLAY 0.638298 (3000 4825);
FORCEPROP 1 LAST VALUE 1000PF
J 0
(3000 4925);
DISPLAY 0.638298 (3000 4925);
FORCEPROP 1 LAST VOLTAGE 50V
J 0
(3000 4875);
DISPLAY 0.638298 (3000 4875);
FORCEPROP 1 LAST MATERIAL EMPTY
J 0
(3000 4775);
DISPLAY 0.638298 (3000 4775);
PAINT RED (3000 4775);
FORCEPROP 1 LAST PACK_TYPE 0402
J 0
(3000 4675);
DISPLAY 0.638298 (3000 4675);
FORCEPROP 1 LAST $LOCATION C1804
J 0
(3000 4975);
DISPLAY 0.638298 (3000 4975);
FORCEPROP 1 LASTPIN (2950 4975) $PN 1
J 0
(2960 4955);
DISPLAY 0.787234 (2960 4955);
PAINT MONO (2960 4955);
FORCEPROP 1 LASTPIN (2950 4775) $PN 2
J 0
(2960 4755);
DISPLAY 0.787234 (2960 4755);
PAINT MONO (2960 4755);
FORCEPROP 2 LAST CDS_LIB pure_quanta
J 0
(2950 4875);
DISPLAY INVISIBLE (2950 4875);
FORCEPROP 1 LAST PATH I125
J 0
(3000 5025);
DISPLAY 0.978723 (3000 5025);
PAINT WHITE (3000 5025);
DISPLAY INVISIBLE (3000 5025);
FORCEPROP 2 LAST CDS_LOCATION C1804
J 0
(3000 5075);
DISPLAY 1.021277 (3000 5075);
DISPLAY INVISIBLE (3000 5075);
FORCEPROP 2 LAST $SEC 1
J 0
(3000 5075);
DISPLAY 0.680851 (3000 5075);
PAINT MONO (3000 5075);
DISPLAY INVISIBLE (3000 5075);
FORCEPROP 2 LAST CDS_SEC 1
J 0
(3000 5075);
DISPLAY 1.021277 (3000 5075);
DISPLAY INVISIBLE (3000 5075);
FORCEADD UNIVERSAL_GND..1
(2950 4675);
FORCEPROP 3 LASTPIN (2950 4725) SIG_NAME GND\g
J 0
(2960 4735);
DISPLAY 0.659574 (2960 4735);
PAINT MONO (2960 4735);
DISPLAY INVISIBLE (2960 4735);
FORCEPROP 2 LAST CDS_LIB logical_power
J 0
(2950 4675);
DISPLAY INVISIBLE (2950 4675);
FORCEPROP 1 LAST HDL_POWER GND
J 1
(2975 4600);
DISPLAY 0.872340 (2975 4600);
PAINT GREEN (2975 4600);
DISPLAY INVISIBLE (2975 4600);
FORCEPROP 1 LAST PATH I126
J 0
(3025 4675);
DISPLAY 0.872340 (3025 4675);
PAINT AQUA (3025 4675);
DISPLAY INVISIBLE (3025 4675);
FORCEADD Q_RES..2
(2050 5500);
FORCEPROP 1 LAST PART_NUMBER CS24702JB10
J 0
(2090 5325);
DISPLAY 0.638298 (2090 5325);
DISPLAY INVISIBLE (2090 5325);
FORCEPROP 1 LAST PACK_TYPE 0402LF
J 0
(2090 5375);
DISPLAY 0.638298 (2090 5375);
FORCEPROP 1 LAST VALUE 4.7K
J 0
(2095 5575);
DISPLAY 0.638298 (2095 5575);
FORCEPROP 1 LAST TOLERANCE 5%
J 0
(2095 5525);
DISPLAY 0.638298 (2095 5525);
FORCEPROP 1 LAST MATERIAL CHIP
J 0
(2090 5425);
DISPLAY 0.638298 (2090 5425);
FORCEPROP 1 LAST WATTAGE 1/16W
J 0
(2090 5475);
DISPLAY 0.638298 (2090 5475);
FORCEPROP 1 LAST $LOCATION R3035
J 0
(2095 5625);
DISPLAY 0.978723 (2095 5625);
FORCEPROP 1 LASTPIN (2050 5600) $PN 1
J 0
(2055 5562);
DISPLAY 0.787234 (2055 5562);
PAINT MONO (2055 5562);
FORCEPROP 1 LASTPIN (2050 5400) $PN 2
J 0
(2055 5410);
DISPLAY 0.787234 (2055 5410);
PAINT MONO (2055 5410);
FORCEPROP 2 LAST CDS_LIB pure_quanta
J 0
(2050 5500);
DISPLAY INVISIBLE (2050 5500);
FORCEPROP 1 LAST PATH I127
J 0
(2100 5675);
DISPLAY 0.978723 (2100 5675);
PAINT WHITE (2100 5675);
DISPLAY INVISIBLE (2100 5675);
FORCEPROP 0 LAST CDS_LOCATION R3035
J 0
(2100 5675);
DISPLAY 1.021277 (2100 5675);
DISPLAY INVISIBLE (2100 5675);
FORCEPROP 0 LAST $SEC 1
J 0
(2100 5675);
DISPLAY 0.680851 (2100 5675);
PAINT MONO (2100 5675);
DISPLAY INVISIBLE (2100 5675);
FORCEPROP 0 LAST CDS_SEC 1
J 0
(2100 5675);
DISPLAY 1.021277 (2100 5675);
DISPLAY INVISIBLE (2100 5675);
FORCEADD UNIVERSAL_POWER..1
(1125 5550);
FORCEPROP 3 LASTPIN (1125 5500) SIG_NAME P3V3_AUX\g
J 0
(1135 5510);
DISPLAY 0.659574 (1135 5510);
PAINT MONO (1135 5510);
DISPLAY INVISIBLE (1135 5510);
FORCEPROP 1 LAST HDL_POWER P3V3_AUX
J 1
(1125 5600);
DISPLAY 0.872340 (1125 5600);
PAINT GREEN (1125 5600);
FORCEPROP 2 LAST CDS_LIB logical_power
J 0
(1125 5550);
PAINT MONO (1125 5550);
DISPLAY INVISIBLE (1125 5550);
FORCEPROP 1 LAST PATH I128
J 0
(1175 5575);
DISPLAY 0.872340 (1175 5575);
PAINT AQUA (1175 5575);
DISPLAY INVISIBLE (1175 5575);
FORCEADD Q_RES..2
(1125 5250);
FORCEPROP 1 LAST PART_NUMBER CS24702JB10
J 0
(1165 5075);
DISPLAY 0.638298 (1165 5075);
DISPLAY INVISIBLE (1165 5075);
FORCEPROP 1 LAST TOLERANCE 5%
J 0
(1170 5275);
DISPLAY 0.638298 (1170 5275);
FORCEPROP 1 LAST VALUE 4.7K
J 0
(1170 5325);
DISPLAY 0.638298 (1170 5325);
FORCEPROP 1 LAST WATTAGE 1/16W
J 0
(1165 5225);
DISPLAY 0.638298 (1165 5225);
FORCEPROP 1 LAST MATERIAL CHIP
J 0
(1165 5175);
DISPLAY 0.638298 (1165 5175);
FORCEPROP 1 LAST PACK_TYPE 0402LF
J 0
(1165 5125);
DISPLAY 0.638298 (1165 5125);
FORCEPROP 1 LAST $LOCATION R3034
J 0
(1170 5375);
DISPLAY 0.638298 (1170 5375);
FORCEPROP 1 LASTPIN (1125 5350) $PN 1
J 0
(1130 5312);
DISPLAY 0.787234 (1130 5312);
FORCEPROP 1 LASTPIN (1125 5150) $PN 2
J 0
(1130 5160);
DISPLAY 0.787234 (1130 5160);
FORCEPROP 2 LAST CDS_LIB pure_quanta
J 0
(1125 5250);
PAINT MONO (1125 5250);
DISPLAY INVISIBLE (1125 5250);
FORCEPROP 1 LAST PATH I129
J 0
(1175 5425);
DISPLAY 0.978723 (1175 5425);
PAINT WHITE (1175 5425);
DISPLAY INVISIBLE (1175 5425);
FORCEPROP 2 LAST CDS_LOCATION R3034
J 0
(1175 5475);
DISPLAY 1.021277 (1175 5475);
DISPLAY INVISIBLE (1175 5475);
FORCEPROP 2 LAST $SEC 1
J 0
(1175 5475);
DISPLAY 0.680851 (1175 5475);
PAINT MONO (1175 5475);
DISPLAY INVISIBLE (1175 5475);
FORCEPROP 2 LAST CDS_SEC 1
J 0
(1175 5475);
DISPLAY 1.021277 (1175 5475);
DISPLAY INVISIBLE (1175 5475);
FORCEADD UNIVERSAL_POWER..1
(-3525 8225);
FORCEPROP 3 LASTPIN (-3525 8175) SIG_NAME P3V3_AUX\g
J 0
(-3515 8185);
DISPLAY 0.659574 (-3515 8185);
PAINT MONO (-3515 8185);
DISPLAY INVISIBLE (-3515 8185);
FORCEPROP 1 LAST HDL_POWER P3V3_AUX
J 1
(-3525 8275);
DISPLAY 0.872340 (-3525 8275);
PAINT GREEN (-3525 8275);
FORCEPROP 1 LAST PATH I13
J 0
(-3475 8250);
DISPLAY 0.872340 (-3475 8250);
PAINT AQUA (-3475 8250);
DISPLAY INVISIBLE (-3475 8250);
FORCEPROP 2 LAST CDS_LIB logical_power
J 0
(-3525 8225);
PAINT MONO (-3525 8225);
DISPLAY INVISIBLE (-3525 8225);
FORCEADD UNIVERSAL_GND..1
(2050 4675);
FORCEPROP 3 LASTPIN (2050 4725) SIG_NAME GND\g
J 0
(2060 4735);
DISPLAY 0.659574 (2060 4735);
PAINT MONO (2060 4735);
DISPLAY INVISIBLE (2060 4735);
FORCEPROP 2 LAST CDS_LIB logical_power
J 0
(2050 4675);
DISPLAY INVISIBLE (2050 4675);
FORCEPROP 1 LAST HDL_POWER GND
J 1
(2075 4600);
DISPLAY 0.872340 (2075 4600);
PAINT GREEN (2075 4600);
DISPLAY INVISIBLE (2075 4600);
FORCEPROP 1 LAST PATH I130
J 0
(2125 4675);
DISPLAY 0.872340 (2125 4675);
PAINT AQUA (2125 4675);
DISPLAY INVISIBLE (2125 4675);
FORCEADD UNIVERSAL_GND..1
(1125 4400);
FORCEPROP 3 LASTPIN (1125 4450) SIG_NAME GND\g
J 0
(1135 4460);
DISPLAY 0.659574 (1135 4460);
PAINT MONO (1135 4460);
DISPLAY INVISIBLE (1135 4460);
FORCEPROP 2 LAST CDS_LIB logical_power
J 0
(1125 4400);
DISPLAY INVISIBLE (1125 4400);
FORCEPROP 1 LAST PATH I131
J 0
(1200 4400);
DISPLAY 0.872340 (1200 4400);
PAINT AQUA (1200 4400);
DISPLAY INVISIBLE (1200 4400);
FORCEPROP 1 LAST HDL_POWER GND
J 1
(1150 4325);
DISPLAY 0.872340 (1150 4325);
PAINT GREEN (1150 4325);
DISPLAY INVISIBLE (1150 4325);
FORCEADD UNIVERSAL_POWER..1
(-125 5250);
FORCEPROP 3 LASTPIN (-125 5200) SIG_NAME P3V3_AUX\g
J 0
(-115 5210);
DISPLAY 0.659574 (-115 5210);
PAINT MONO (-115 5210);
DISPLAY INVISIBLE (-115 5210);
FORCEPROP 1 LAST HDL_POWER P3V3_AUX
J 1
(-125 5300);
DISPLAY 0.872340 (-125 5300);
PAINT GREEN (-125 5300);
FORCEPROP 2 LAST CDS_LIB logical_power
J 0
(-125 5250);
PAINT MONO (-125 5250);
DISPLAY INVISIBLE (-125 5250);
FORCEPROP 1 LAST PATH I132
J 0
(-75 5275);
DISPLAY 0.872340 (-75 5275);
PAINT AQUA (-75 5275);
DISPLAY INVISIBLE (-75 5275);
FORCEADD Q_RES..2
(-100 4525);
FORCEPROP 1 LAST PART_NUMBER CS41002FB09
J 0
(-60 4400);
DISPLAY 0.510638 (-60 4400);
DISPLAY INVISIBLE (-60 4400);
FORCEPROP 1 LAST PACK_TYPE 0402LF
J 0
(-60 4350);
DISPLAY 0.510638 (-60 4350);
FORCEPROP 1 LAST MATERIAL EMPTY
J 0
(-60 4450);
DISPLAY 0.510638 (-60 4450);
FORCEPROP 1 LAST WATTAGE 1/16W
J 0
(-60 4500);
DISPLAY 0.510638 (-60 4500);
FORCEPROP 1 LAST TOLERANCE 1%
J 0
(-55 4550);
DISPLAY 0.510638 (-55 4550);
FORCEPROP 1 LAST VALUE 100K
J 0
(-55 4600);
DISPLAY 0.510638 (-55 4600);
FORCEPROP 1 LAST $LOCATION R3032
J 0
(-55 4650);
DISPLAY 0.978723 (-55 4650);
FORCEPROP 1 LASTPIN (-100 4625) $PN 1
J 0
(-95 4587);
DISPLAY 0.787234 (-95 4587);
PAINT MONO (-95 4587);
FORCEPROP 1 LASTPIN (-100 4425) $PN 2
J 0
(-95 4435);
DISPLAY 0.787234 (-95 4435);
PAINT MONO (-95 4435);
FORCEPROP 1 LAST PATH I134
J 0
(-50 4700);
DISPLAY 0.978723 (-50 4700);
PAINT WHITE (-50 4700);
DISPLAY INVISIBLE (-50 4700);
FORCEPROP 2 LAST CDS_LIB pure_quanta
J 0
(-100 4525);
DISPLAY INVISIBLE (-100 4525);
FORCEPROP 0 LAST CDS_LOCATION R3032
J 0
(-50 4700);
DISPLAY 1.021277 (-50 4700);
DISPLAY INVISIBLE (-50 4700);
FORCEPROP 0 LAST $SEC 1
J 0
(-50 4700);
DISPLAY 0.680851 (-50 4700);
PAINT MONO (-50 4700);
DISPLAY INVISIBLE (-50 4700);
FORCEPROP 0 LAST CDS_SEC 1
J 0
(-50 4700);
DISPLAY 1.021277 (-50 4700);
DISPLAY INVISIBLE (-50 4700);
FORCEADD UNIVERSAL_GND..1
(-100 4325);
FORCEPROP 3 LASTPIN (-100 4375) SIG_NAME GND\g
J 0
(-90 4385);
DISPLAY 0.659574 (-90 4385);
PAINT MONO (-90 4385);
DISPLAY INVISIBLE (-90 4385);
FORCEPROP 1 LAST PATH I135
J 0
(-25 4325);
DISPLAY 0.872340 (-25 4325);
PAINT AQUA (-25 4325);
DISPLAY INVISIBLE (-25 4325);
FORCEPROP 2 LAST CDS_LIB logical_power
J 0
(-100 4325);
DISPLAY INVISIBLE (-100 4325);
FORCEPROP 1 LAST HDL_POWER GND
J 1
(-75 4250);
DISPLAY 0.872340 (-75 4250);
PAINT GREEN (-75 4250);
DISPLAY INVISIBLE (-75 4250);
FORCEADD OFFPAGE..4
R 2
(-400 4725);
FORCEPROP 2 LAST $XR0 141 
J 0
(-652 4725);
DISPLAY 0.638298 (-652 4725);
PAINT MONO (-652 4725);
FORCEPROP 2 LAST CDS_LIB standard
J 0
(-400 4725);
DISPLAY INVISIBLE (-400 4725);
FORCEPROP 1 LAST COMMENT_BODY TRUE
J 2
(-375 4625);
DISPLAY 0.872340 (-375 4625);
PAINT GREEN (-375 4625);
DISPLAY INVISIBLE (-375 4625);
FORCEPROP 1 LAST OFFPAGE TRUE
J 2
(-725 4600);
DISPLAY 0.872340 (-725 4600);
PAINT GREEN (-725 4600);
DISPLAY INVISIBLE (-725 4600);
FORCEPROP 2 LAST PATH I136
J 0
(-650 4775);
DISPLAY 1.021277 (-650 4775);
DISPLAY INVISIBLE (-650 4775);
FORCEADD OFFPAGE..4
R 2
(-4950 3025);
FORCEPROP 2 LAST $XR0 141 
J 0
(-5232 3025);
DISPLAY 0.638298 (-5232 3025);
PAINT MONO (-5232 3025);
FORCEPROP 2 LAST PATH I137
J 0
(-5200 3075);
DISPLAY 1.021277 (-5200 3075);
DISPLAY INVISIBLE (-5200 3075);
FORCEPROP 1 LAST OFFPAGE TRUE
J 2
(-5275 2900);
DISPLAY 0.872340 (-5275 2900);
PAINT GREEN (-5275 2900);
DISPLAY INVISIBLE (-5275 2900);
FORCEPROP 1 LAST COMMENT_BODY TRUE
J 2
(-4925 2925);
DISPLAY 0.872340 (-4925 2925);
PAINT GREEN (-4925 2925);
DISPLAY INVISIBLE (-4925 2925);
FORCEPROP 2 LAST CDS_LIB standard
J 0
(-4950 3025);
DISPLAY INVISIBLE (-4950 3025);
FORCEADD UNIVERSAL_GND..1
(-4650 2625);
FORCEPROP 3 LASTPIN (-4650 2675) SIG_NAME GND\g
J 0
(-4640 2685);
DISPLAY 0.659574 (-4640 2685);
PAINT MONO (-4640 2685);
DISPLAY INVISIBLE (-4640 2685);
FORCEPROP 2 LAST CDS_LIB logical_power
J 0
(-4650 2625);
DISPLAY INVISIBLE (-4650 2625);
FORCEPROP 1 LAST HDL_POWER GND
J 1
(-4625 2550);
DISPLAY 0.872340 (-4625 2550);
PAINT GREEN (-4625 2550);
DISPLAY INVISIBLE (-4625 2550);
FORCEPROP 1 LAST PATH I138
J 0
(-4575 2625);
DISPLAY 0.872340 (-4575 2625);
PAINT AQUA (-4575 2625);
DISPLAY INVISIBLE (-4575 2625);
FORCEADD Q_RES..2
(-4650 2825);
FORCEPROP 1 LAST PART_NUMBER CS41002FB09
J 0
(-4610 2700);
DISPLAY 0.510638 (-4610 2700);
DISPLAY INVISIBLE (-4610 2700);
FORCEPROP 1 LAST WATTAGE 1/16W
J 0
(-4610 2800);
DISPLAY 0.510638 (-4610 2800);
FORCEPROP 1 LAST VALUE 100K
J 0
(-4605 2900);
DISPLAY 0.510638 (-4605 2900);
FORCEPROP 1 LAST MATERIAL EMPTY
J 0
(-4610 2750);
DISPLAY 0.510638 (-4610 2750);
FORCEPROP 1 LAST TOLERANCE 1%
J 0
(-4605 2850);
DISPLAY 0.510638 (-4605 2850);
FORCEPROP 1 LAST PACK_TYPE 0402LF
J 0
(-4610 2650);
DISPLAY 0.510638 (-4610 2650);
FORCEPROP 1 LAST $LOCATION R3028
J 0
(-4605 2950);
DISPLAY 0.978723 (-4605 2950);
FORCEPROP 1 LASTPIN (-4650 2925) $PN 1
J 0
(-4645 2887);
DISPLAY 0.787234 (-4645 2887);
PAINT MONO (-4645 2887);
FORCEPROP 1 LASTPIN (-4650 2725) $PN 2
J 0
(-4645 2735);
DISPLAY 0.787234 (-4645 2735);
PAINT MONO (-4645 2735);
FORCEPROP 2 LAST CDS_LIB pure_quanta
J 0
(-4650 2825);
DISPLAY INVISIBLE (-4650 2825);
FORCEPROP 1 LAST PATH I139
J 0
(-4600 3000);
DISPLAY 0.978723 (-4600 3000);
PAINT WHITE (-4600 3000);
DISPLAY INVISIBLE (-4600 3000);
FORCEPROP 0 LAST CDS_LOCATION R3028
J 0
(-4600 3000);
DISPLAY 1.021277 (-4600 3000);
DISPLAY INVISIBLE (-4600 3000);
FORCEPROP 0 LAST $SEC 1
J 0
(-4600 3000);
DISPLAY 0.680851 (-4600 3000);
PAINT MONO (-4600 3000);
DISPLAY INVISIBLE (-4600 3000);
FORCEPROP 0 LAST CDS_SEC 1
J 0
(-4600 3000);
DISPLAY 1.021277 (-4600 3000);
DISPLAY INVISIBLE (-4600 3000);
FORCEADD Q_RES..2
(-3525 8000);
FORCEPROP 1 LAST PART_NUMBER CS24702JB10
J 0
(-3485 7825);
DISPLAY 0.638298 (-3485 7825);
DISPLAY INVISIBLE (-3485 7825);
FORCEPROP 1 LAST PACK_TYPE 0402LF
J 0
(-3485 7875);
DISPLAY 0.638298 (-3485 7875);
FORCEPROP 1 LAST VALUE 4.7K
J 0
(-3480 8075);
DISPLAY 0.638298 (-3480 8075);
FORCEPROP 1 LAST TOLERANCE 5%
J 0
(-3480 8025);
DISPLAY 0.638298 (-3480 8025);
FORCEPROP 1 LAST WATTAGE 1/16W
J 0
(-3485 7975);
DISPLAY 0.638298 (-3485 7975);
FORCEPROP 1 LAST MATERIAL CHIP
J 0
(-3485 7925);
DISPLAY 0.638298 (-3485 7925);
FORCEPROP 1 LAST $LOCATION R2835
J 0
(-3480 8125);
DISPLAY 0.638298 (-3480 8125);
FORCEPROP 1 LASTPIN (-3525 8100) $PN 1
J 0
(-3520 8062);
DISPLAY 0.787234 (-3520 8062);
FORCEPROP 1 LASTPIN (-3525 7900) $PN 2
J 0
(-3520 7910);
DISPLAY 0.787234 (-3520 7910);
FORCEPROP 1 LAST PATH I14
J 0
(-3475 8175);
DISPLAY 0.978723 (-3475 8175);
PAINT WHITE (-3475 8175);
DISPLAY INVISIBLE (-3475 8175);
FORCEPROP 2 LAST CDS_LIB pure_quanta
J 0
(-3525 8000);
PAINT MONO (-3525 8000);
DISPLAY INVISIBLE (-3525 8000);
FORCEPROP 2 LAST CDS_LOCATION R2835
J 0
(-3475 8225);
DISPLAY 1.021277 (-3475 8225);
DISPLAY INVISIBLE (-3475 8225);
FORCEPROP 2 LAST $SEC 1
J 0
(-3475 8225);
DISPLAY 0.680851 (-3475 8225);
PAINT MONO (-3475 8225);
DISPLAY INVISIBLE (-3475 8225);
FORCEPROP 2 LAST CDS_SEC 1
J 0
(-3475 8225);
DISPLAY 1.021277 (-3475 8225);
DISPLAY INVISIBLE (-3475 8225);
FORCEADD UNIVERSAL_POWER..1
(-4675 3550);
FORCEPROP 3 LASTPIN (-4675 3500) SIG_NAME P3V3_AUX\g
J 0
(-4665 3510);
DISPLAY 0.659574 (-4665 3510);
PAINT MONO (-4665 3510);
DISPLAY INVISIBLE (-4665 3510);
FORCEPROP 1 LAST HDL_POWER P3V3_AUX
J 1
(-4675 3600);
DISPLAY 0.872340 (-4675 3600);
PAINT GREEN (-4675 3600);
FORCEPROP 1 LAST PATH I141
J 0
(-4625 3575);
DISPLAY 0.872340 (-4625 3575);
PAINT AQUA (-4625 3575);
DISPLAY INVISIBLE (-4625 3575);
FORCEPROP 2 LAST CDS_LIB logical_power
J 0
(-4675 3550);
PAINT MONO (-4675 3550);
DISPLAY INVISIBLE (-4675 3550);
FORCEADD UNIVERSAL_GND..1
(-3425 2700);
FORCEPROP 3 LASTPIN (-3425 2750) SIG_NAME GND\g
J 0
(-3415 2760);
DISPLAY 0.659574 (-3415 2760);
PAINT MONO (-3415 2760);
DISPLAY INVISIBLE (-3415 2760);
FORCEPROP 1 LAST PATH I142
J 0
(-3350 2700);
DISPLAY 0.872340 (-3350 2700);
PAINT AQUA (-3350 2700);
DISPLAY INVISIBLE (-3350 2700);
FORCEPROP 1 LAST HDL_POWER GND
J 1
(-3400 2625);
DISPLAY 0.872340 (-3400 2625);
PAINT GREEN (-3400 2625);
DISPLAY INVISIBLE (-3400 2625);
FORCEPROP 2 LAST CDS_LIB logical_power
J 0
(-3425 2700);
DISPLAY INVISIBLE (-3425 2700);
FORCEADD UNIVERSAL_GND..1
(-2500 2975);
FORCEPROP 3 LASTPIN (-2500 3025) SIG_NAME GND\g
J 0
(-2490 3035);
DISPLAY 0.659574 (-2490 3035);
PAINT MONO (-2490 3035);
DISPLAY INVISIBLE (-2490 3035);
FORCEPROP 1 LAST PATH I143
J 0
(-2425 2975);
DISPLAY 0.872340 (-2425 2975);
PAINT AQUA (-2425 2975);
DISPLAY INVISIBLE (-2425 2975);
FORCEPROP 2 LAST CDS_LIB logical_power
J 0
(-2500 2975);
DISPLAY INVISIBLE (-2500 2975);
FORCEPROP 1 LAST HDL_POWER GND
J 1
(-2475 2900);
DISPLAY 0.872340 (-2475 2900);
PAINT GREEN (-2475 2900);
DISPLAY INVISIBLE (-2475 2900);
FORCEADD Q_RES..2
(-3425 3550);
FORCEPROP 1 LAST PART_NUMBER CS24702JB10
J 0
(-3385 3375);
DISPLAY 0.638298 (-3385 3375);
DISPLAY INVISIBLE (-3385 3375);
FORCEPROP 1 LAST VALUE 4.7K
J 0
(-3380 3625);
DISPLAY 0.638298 (-3380 3625);
FORCEPROP 1 LAST PACK_TYPE 0402LF
J 0
(-3385 3425);
DISPLAY 0.638298 (-3385 3425);
FORCEPROP 1 LAST WATTAGE 1/16W
J 0
(-3385 3525);
DISPLAY 0.638298 (-3385 3525);
FORCEPROP 1 LAST MATERIAL CHIP
J 0
(-3385 3475);
DISPLAY 0.638298 (-3385 3475);
FORCEPROP 1 LAST TOLERANCE 5%
J 0
(-3380 3575);
DISPLAY 0.638298 (-3380 3575);
FORCEPROP 1 LAST $LOCATION R3029
J 0
(-3380 3675);
DISPLAY 0.638298 (-3380 3675);
FORCEPROP 1 LASTPIN (-3425 3650) $PN 1
J 0
(-3420 3612);
DISPLAY 0.787234 (-3420 3612);
FORCEPROP 1 LASTPIN (-3425 3450) $PN 2
J 0
(-3420 3460);
DISPLAY 0.787234 (-3420 3460);
FORCEPROP 1 LAST PATH I144
J 0
(-3375 3725);
DISPLAY 0.978723 (-3375 3725);
PAINT WHITE (-3375 3725);
DISPLAY INVISIBLE (-3375 3725);
FORCEPROP 2 LAST CDS_LIB pure_quanta
J 0
(-3425 3550);
PAINT MONO (-3425 3550);
DISPLAY INVISIBLE (-3425 3550);
FORCEPROP 2 LAST CDS_LOCATION R3029
J 0
(-3375 3775);
DISPLAY 1.021277 (-3375 3775);
DISPLAY INVISIBLE (-3375 3775);
FORCEPROP 2 LAST $SEC 1
J 0
(-3375 3775);
DISPLAY 0.680851 (-3375 3775);
PAINT MONO (-3375 3775);
DISPLAY INVISIBLE (-3375 3775);
FORCEPROP 2 LAST CDS_SEC 1
J 0
(-3375 3775);
DISPLAY 1.021277 (-3375 3775);
DISPLAY INVISIBLE (-3375 3775);
FORCEADD UNIVERSAL_POWER..1
(-3425 3850);
FORCEPROP 3 LASTPIN (-3425 3800) SIG_NAME P3V3_AUX\g
J 0
(-3415 3810);
DISPLAY 0.659574 (-3415 3810);
PAINT MONO (-3415 3810);
DISPLAY INVISIBLE (-3415 3810);
FORCEPROP 1 LAST HDL_POWER P3V3_AUX
J 1
(-3425 3900);
DISPLAY 0.872340 (-3425 3900);
PAINT GREEN (-3425 3900);
FORCEPROP 1 LAST PATH I145
J 0
(-3375 3875);
DISPLAY 0.872340 (-3375 3875);
PAINT AQUA (-3375 3875);
DISPLAY INVISIBLE (-3375 3875);
FORCEPROP 2 LAST CDS_LIB logical_power
J 0
(-3425 3850);
PAINT MONO (-3425 3850);
DISPLAY INVISIBLE (-3425 3850);
FORCEADD Q_RES..2
(-2500 3800);
FORCEPROP 1 LAST PART_NUMBER CS24702JB10
J 0
(-2460 3625);
DISPLAY 0.638298 (-2460 3625);
DISPLAY INVISIBLE (-2460 3625);
FORCEPROP 1 LAST VALUE 4.7K
J 0
(-2455 3875);
DISPLAY 0.638298 (-2455 3875);
FORCEPROP 1 LAST WATTAGE 1/16W
J 0
(-2460 3775);
DISPLAY 0.638298 (-2460 3775);
FORCEPROP 1 LAST PACK_TYPE 0402LF
J 0
(-2460 3675);
DISPLAY 0.638298 (-2460 3675);
FORCEPROP 1 LAST MATERIAL CHIP
J 0
(-2460 3725);
DISPLAY 0.638298 (-2460 3725);
FORCEPROP 1 LAST TOLERANCE 5%
J 0
(-2455 3825);
DISPLAY 0.638298 (-2455 3825);
FORCEPROP 1 LAST $LOCATION R3030
J 0
(-2455 3925);
DISPLAY 0.978723 (-2455 3925);
FORCEPROP 1 LASTPIN (-2500 3900) $PN 1
J 0
(-2495 3862);
DISPLAY 0.787234 (-2495 3862);
PAINT MONO (-2495 3862);
FORCEPROP 1 LASTPIN (-2500 3700) $PN 2
J 0
(-2495 3710);
DISPLAY 0.787234 (-2495 3710);
PAINT MONO (-2495 3710);
FORCEPROP 1 LAST PATH I146
J 0
(-2450 3975);
DISPLAY 0.978723 (-2450 3975);
PAINT WHITE (-2450 3975);
DISPLAY INVISIBLE (-2450 3975);
FORCEPROP 2 LAST CDS_LIB pure_quanta
J 0
(-2500 3800);
DISPLAY INVISIBLE (-2500 3800);
FORCEPROP 0 LAST CDS_LOCATION R3030
J 0
(-2450 3975);
DISPLAY 1.021277 (-2450 3975);
DISPLAY INVISIBLE (-2450 3975);
FORCEPROP 0 LAST $SEC 1
J 0
(-2450 3975);
DISPLAY 0.680851 (-2450 3975);
PAINT MONO (-2450 3975);
DISPLAY INVISIBLE (-2450 3975);
FORCEPROP 0 LAST CDS_SEC 1
J 0
(-2450 3975);
DISPLAY 1.021277 (-2450 3975);
DISPLAY INVISIBLE (-2450 3975);
FORCEADD UNIVERSAL_GND..1
(-1600 2975);
FORCEPROP 3 LASTPIN (-1600 3025) SIG_NAME GND\g
J 0
(-1590 3035);
DISPLAY 0.659574 (-1590 3035);
PAINT MONO (-1590 3035);
DISPLAY INVISIBLE (-1590 3035);
FORCEPROP 1 LAST PATH I147
J 0
(-1525 2975);
DISPLAY 0.872340 (-1525 2975);
PAINT AQUA (-1525 2975);
DISPLAY INVISIBLE (-1525 2975);
FORCEPROP 2 LAST CDS_LIB logical_power
J 0
(-1600 2975);
DISPLAY INVISIBLE (-1600 2975);
FORCEPROP 1 LAST HDL_POWER GND
J 1
(-1575 2900);
DISPLAY 0.872340 (-1575 2900);
PAINT GREEN (-1575 2900);
DISPLAY INVISIBLE (-1575 2900);
FORCEADD Q_CAP..1
(-1600 3175);
FORCEPROP 1 LAST PART_NUMBER TMP_QCH21006JB10
J 0
(-1550 3025);
DISPLAY 0.638298 (-1550 3025);
DISPLAY INVISIBLE (-1550 3025);
FORCEPROP 1 LAST VALUE 1000PF
J 0
(-1550 3225);
DISPLAY 0.638298 (-1550 3225);
FORCEPROP 1 LAST VOLTAGE 50V
J 0
(-1550 3175);
DISPLAY 0.638298 (-1550 3175);
FORCEPROP 1 LAST PACK_TYPE 0402
J 0
(-1550 2975);
DISPLAY 0.638298 (-1550 2975);
FORCEPROP 1 LAST TOLERANCE 5%
J 0
(-1550 3125);
DISPLAY 0.638298 (-1550 3125);
FORCEPROP 1 LAST MATERIAL EMPTY
J 0
(-1550 3075);
DISPLAY 0.638298 (-1550 3075);
PAINT RED (-1550 3075);
FORCEPROP 1 LAST $LOCATION C1802
J 0
(-1550 3275);
DISPLAY 0.638298 (-1550 3275);
FORCEPROP 1 LASTPIN (-1600 3275) $PN 1
J 0
(-1590 3255);
DISPLAY 0.787234 (-1590 3255);
PAINT MONO (-1590 3255);
FORCEPROP 1 LASTPIN (-1600 3075) $PN 2
J 0
(-1590 3055);
DISPLAY 0.787234 (-1590 3055);
PAINT MONO (-1590 3055);
FORCEPROP 1 LAST PATH I148
J 0
(-1550 3325);
DISPLAY 0.978723 (-1550 3325);
PAINT WHITE (-1550 3325);
DISPLAY INVISIBLE (-1550 3325);
FORCEPROP 2 LAST CDS_LIB pure_quanta
J 0
(-1600 3175);
DISPLAY INVISIBLE (-1600 3175);
FORCEPROP 2 LAST CDS_LOCATION C1802
J 0
(-1550 3375);
DISPLAY 1.021277 (-1550 3375);
DISPLAY INVISIBLE (-1550 3375);
FORCEPROP 2 LAST $SEC 1
J 0
(-1550 3375);
DISPLAY 0.680851 (-1550 3375);
PAINT MONO (-1550 3375);
DISPLAY INVISIBLE (-1550 3375);
FORCEPROP 2 LAST CDS_SEC 1
J 0
(-1550 3375);
DISPLAY 1.021277 (-1550 3375);
DISPLAY INVISIBLE (-1550 3375);
FORCEADD OFFPAGE..2
(-1325 3575);
FORCEPROP 2 LAST $XR0 214 
J 0
(-1136 3575);
DISPLAY 0.638298 (-1136 3575);
PAINT MONO (-1136 3575);
FORCEPROP 2 LAST PATH I149
J 0
(-1125 3625);
DISPLAY 1.021277 (-1125 3625);
DISPLAY INVISIBLE (-1125 3625);
FORCEPROP 1 LAST OFFPAGE TRUE
J 0
(-1000 3450);
DISPLAY 0.872340 (-1000 3450);
PAINT AQUA (-1000 3450);
DISPLAY INVISIBLE (-1000 3450);
FORCEPROP 1 LAST COMMENT_BODY TRUE
J 0
(-1370 3480);
DISPLAY 0.872340 (-1370 3480);
PAINT GREEN (-1370 3480);
DISPLAY INVISIBLE (-1370 3480);
FORCEPROP 2 LAST CDS_LIB standard
J 0
(-1325 3575);
DISPLAY INVISIBLE (-1325 3575);
FORCEADD UNIVERSAL_POWER..1
(-2500 4100);
FORCEPROP 3 LASTPIN (-2500 4050) SIG_NAME P3V3_AUX\g
J 0
(-2490 4060);
DISPLAY 0.659574 (-2490 4060);
PAINT MONO (-2490 4060);
DISPLAY INVISIBLE (-2490 4060);
FORCEPROP 1 LAST HDL_POWER P3V3_AUX
J 1
(-2500 4150);
DISPLAY 0.872340 (-2500 4150);
PAINT GREEN (-2500 4150);
FORCEPROP 1 LAST PATH I150
J 0
(-2450 4125);
DISPLAY 0.872340 (-2450 4125);
PAINT AQUA (-2450 4125);
DISPLAY INVISIBLE (-2450 4125);
FORCEPROP 2 LAST CDS_LIB logical_power
J 0
(-2500 4100);
DISPLAY INVISIBLE (-2500 4100);
FORCEADD MOSFET_NCH_DUAL..2
(-2550 3350);
FORCEPROP 1 LAST PART_NUMBER BAM138K0003
J 0
(-2399 3256);
DISPLAY 0.723404 (-2399 3256);
PAINT GREEN (-2399 3256);
DISPLAY INVISIBLE (-2399 3256);
FORCEPROP 2 LAST VALUE PJT138K
J 0
(-2375 3375);
DISPLAY 1.021277 (-2375 3375);
FORCEPROP 1 LAST MATERIAL IC
J 0
(-2399 3201);
DISPLAY 0.723404 (-2399 3201);
PAINT GREEN (-2399 3201);
FORCEPROP 2 LAST PART_TYPE SMLF
J 0
(-2375 3425);
DISPLAY 1.021277 (-2375 3425);
FORCEPROP 1 LAST LOCATION Q75
J 0
(-2399 3326);
DISPLAY 0.723404 (-2399 3326);
PAINT GREEN (-2399 3326);
FORCEPROP 0 LASTPIN (-2500 3550) $PN 3
R 1
J 0
(-2510 3560);
DISPLAY 0.680851 (-2510 3560);
PAINT MONO (-2510 3560);
FORCEPROP 0 LASTPIN (-2750 3300) $PN 5
J 2
(-2760 3310);
DISPLAY 0.680851 (-2760 3310);
PAINT MONO (-2760 3310);
FORCEPROP 0 LASTPIN (-2500 3150) $PN 4
R 1
J 2
(-2510 3140);
DISPLAY 0.680851 (-2510 3140);
PAINT MONO (-2510 3140);
FORCEPROP 1 LAST PATH I151
J 0
(-2400 3200);
DISPLAY 0.723404 (-2400 3200);
PAINT GREEN (-2400 3200);
DISPLAY INVISIBLE (-2400 3200);
FORCEPROP 2 LAST CDS_LIB pure_quanta
J 0
(-2550 3350);
DISPLAY INVISIBLE (-2550 3350);
FORCEPROP 1 LAST NEEDS_NO_SIZE TRUE
J 0
(-2400 3241);
DISPLAY 0.468085 (-2400 3241);
PAINT GREEN (-2400 3241);
DISPLAY INVISIBLE (-2400 3241);
FORCEPROP 1 LAST CDS_LMAN_SYM_OUTLINE -150,150,150,-150
J 0
(-2550 3350);
DISPLAY 0.468085 (-2550 3350);
PAINT GREEN (-2550 3350);
DISPLAY INVISIBLE (-2550 3350);
FORCEPROP 0 LAST $SEC 2
J 0
(-2375 3475);
DISPLAY 0.680851 (-2375 3475);
PAINT MONO (-2375 3475);
DISPLAY INVISIBLE (-2375 3475);
FORCEPROP 0 LAST CDS_SEC 2
J 0
(-2375 3475);
DISPLAY 1.021277 (-2375 3475);
DISPLAY INVISIBLE (-2375 3475);
FORCEADD MOSFET_NCH_DUAL..1
(-3475 3075);
FORCEPROP 1 LAST PART_NUMBER BAM138K0003
J 0
(-3324 2989);
DISPLAY 0.723404 (-3324 2989);
PAINT GREEN (-3324 2989);
DISPLAY INVISIBLE (-3324 2989);
FORCEPROP 2 LAST VALUE PJT138K
J 0
(-3300 3100);
DISPLAY 1.021277 (-3300 3100);
FORCEPROP 2 LAST PART_TYPE SMLF
J 0
(-3300 3150);
DISPLAY 1.021277 (-3300 3150);
FORCEPROP 1 LAST MATERIAL IC
J 0
(-3324 2924);
DISPLAY 0.723404 (-3324 2924);
PAINT GREEN (-3324 2924);
FORCEPROP 1 LAST LOCATION Q75
J 0
(-3324 3049);
DISPLAY 0.723404 (-3324 3049);
PAINT GREEN (-3324 3049);
FORCEPROP 0 LASTPIN (-3425 3275) $PN 6
R 1
J 0
(-3435 3285);
DISPLAY 0.680851 (-3435 3285);
PAINT MONO (-3435 3285);
FORCEPROP 0 LASTPIN (-3675 3025) $PN 2
J 2
(-3685 3035);
DISPLAY 0.680851 (-3685 3035);
PAINT MONO (-3685 3035);
FORCEPROP 0 LASTPIN (-3425 2875) $PN 1
R 1
J 2
(-3435 2865);
DISPLAY 0.680851 (-3435 2865);
PAINT MONO (-3435 2865);
FORCEPROP 1 LAST PATH I152
J 0
(-3475 3075);
DISPLAY 0.723404 (-3475 3075);
PAINT GREEN (-3475 3075);
DISPLAY INVISIBLE (-3475 3075);
FORCEPROP 2 LAST CDS_LIB pure_quanta
J 0
(-3475 3075);
DISPLAY INVISIBLE (-3475 3075);
FORCEPROP 1 LAST NEEDS_NO_SIZE TRUE
J 0
(-3475 3074);
DISPLAY 0.468085 (-3475 3074);
PAINT GREEN (-3475 3074);
DISPLAY INVISIBLE (-3475 3074);
FORCEPROP 1 LAST CDS_LMAN_SYM_OUTLINE -150,150,150,-150
J 0
(-3475 3075);
DISPLAY 0.468085 (-3475 3075);
PAINT GREEN (-3475 3075);
DISPLAY INVISIBLE (-3475 3075);
FORCEPROP 0 LAST $SEC 1
J 0
(-3300 3200);
DISPLAY 0.680851 (-3300 3200);
PAINT MONO (-3300 3200);
DISPLAY INVISIBLE (-3300 3200);
FORCEPROP 2 LAST CDS_SEC 1
J 0
(-3300 3200);
DISPLAY 1.021277 (-3300 3200);
DISPLAY INVISIBLE (-3300 3200);
FORCEADD UNIVERSAL_POWER..1
(2000 4250);
FORCEPROP 3 LASTPIN (2000 4200) SIG_NAME P3V3_AUX\g
J 0
(2010 4210);
DISPLAY 0.659574 (2010 4210);
PAINT MONO (2010 4210);
DISPLAY INVISIBLE (2010 4210);
FORCEPROP 1 LAST HDL_POWER P3V3_AUX
J 1
(2000 4300);
DISPLAY 0.872340 (2000 4300);
PAINT GREEN (2000 4300);
FORCEPROP 2 LAST CDS_LIB logical_power
J 0
(2000 4250);
DISPLAY INVISIBLE (2000 4250);
FORCEPROP 1 LAST PATH I153
J 0
(2050 4275);
DISPLAY 0.872340 (2050 4275);
PAINT AQUA (2050 4275);
DISPLAY INVISIBLE (2050 4275);
FORCEADD MOSFET_NCH_DUAL..1
(1025 3225);
FORCEPROP 1 LAST PART_NUMBER BAM138K0003
J 0
(1176 3139);
DISPLAY 0.723404 (1176 3139);
PAINT GREEN (1176 3139);
DISPLAY INVISIBLE (1176 3139);
FORCEPROP 1 LAST MATERIAL IC
J 0
(1176 3074);
DISPLAY 0.723404 (1176 3074);
PAINT GREEN (1176 3074);
FORCEPROP 2 LAST VALUE PJT138K
J 0
(1200 3250);
DISPLAY 1.021277 (1200 3250);
FORCEPROP 2 LAST PART_TYPE SMLF
J 0
(1200 3300);
DISPLAY 1.021277 (1200 3300);
FORCEPROP 1 LAST $LOCATION Q96
J 0
(1176 3199);
DISPLAY 0.723404 (1176 3199);
PAINT GREEN (1176 3199);
FORCEPROP 0 LASTPIN (1075 3425) $PN 6
R 1
J 0
(1065 3435);
DISPLAY 0.680851 (1065 3435);
PAINT MONO (1065 3435);
FORCEPROP 0 LASTPIN (825 3175) $PN 2
J 2
(815 3185);
DISPLAY 0.680851 (815 3185);
PAINT MONO (815 3185);
FORCEPROP 0 LASTPIN (1075 3025) $PN 1
R 1
J 2
(1065 3015);
DISPLAY 0.680851 (1065 3015);
PAINT MONO (1065 3015);
FORCEPROP 1 LAST CDS_LMAN_SYM_OUTLINE -150,150,150,-150
J 0
(1025 3225);
DISPLAY 0.468085 (1025 3225);
PAINT GREEN (1025 3225);
DISPLAY INVISIBLE (1025 3225);
FORCEPROP 1 LAST NEEDS_NO_SIZE TRUE
J 0
(1025 3224);
DISPLAY 0.468085 (1025 3224);
PAINT GREEN (1025 3224);
DISPLAY INVISIBLE (1025 3224);
FORCEPROP 2 LAST CDS_LIB pure_quanta
J 0
(1025 3225);
DISPLAY INVISIBLE (1025 3225);
FORCEPROP 1 LAST PATH I154
J 0
(1025 3225);
DISPLAY 0.723404 (1025 3225);
PAINT GREEN (1025 3225);
DISPLAY INVISIBLE (1025 3225);
FORCEPROP 0 LAST CDS_LOCATION Q96
J 0
(1200 3350);
DISPLAY 1.021277 (1200 3350);
DISPLAY INVISIBLE (1200 3350);
FORCEPROP 0 LAST $SEC 1
J 0
(1200 3350);
DISPLAY 0.680851 (1200 3350);
PAINT MONO (1200 3350);
DISPLAY INVISIBLE (1200 3350);
FORCEPROP 2 LAST CDS_SEC 1
J 0
(1200 3350);
DISPLAY 1.021277 (1200 3350);
DISPLAY INVISIBLE (1200 3350);
FORCEADD OFFPAGE..2
(3175 3725);
FORCEPROP 2 LAST $XR0 213 
J 0
(3364 3725);
DISPLAY 0.638298 (3364 3725);
PAINT MONO (3364 3725);
FORCEPROP 2 LAST CDS_LIB standard
J 0
(3175 3725);
DISPLAY INVISIBLE (3175 3725);
FORCEPROP 2 LAST PATH I155
J 0
(3375 3775);
DISPLAY 1.021277 (3375 3775);
DISPLAY INVISIBLE (3375 3775);
FORCEPROP 1 LAST OFFPAGE TRUE
J 0
(3500 3600);
DISPLAY 0.872340 (3500 3600);
PAINT AQUA (3500 3600);
DISPLAY INVISIBLE (3500 3600);
FORCEPROP 1 LAST COMMENT_BODY TRUE
J 0
(3130 3630);
DISPLAY 0.872340 (3130 3630);
PAINT GREEN (3130 3630);
DISPLAY INVISIBLE (3130 3630);
FORCEADD Q_CAP..1
(2900 3325);
FORCEPROP 1 LAST PART_NUMBER TMP_QCH21006JB10
J 0
(2950 3175);
DISPLAY 0.638298 (2950 3175);
DISPLAY INVISIBLE (2950 3175);
FORCEPROP 1 LAST TOLERANCE 5%
J 0
(2950 3275);
DISPLAY 0.638298 (2950 3275);
FORCEPROP 1 LAST VALUE 1000PF
J 0
(2950 3375);
DISPLAY 0.638298 (2950 3375);
FORCEPROP 1 LAST MATERIAL EMPTY
J 0
(2950 3225);
DISPLAY 0.638298 (2950 3225);
PAINT RED (2950 3225);
FORCEPROP 1 LAST VOLTAGE 50V
J 0
(2950 3325);
DISPLAY 0.638298 (2950 3325);
FORCEPROP 1 LAST PACK_TYPE 0402
J 0
(2950 3125);
DISPLAY 0.638298 (2950 3125);
FORCEPROP 1 LAST $LOCATION C1881
J 0
(2950 3425);
DISPLAY 0.638298 (2950 3425);
FORCEPROP 1 LASTPIN (2900 3425) $PN 1
J 0
(2910 3405);
DISPLAY 0.787234 (2910 3405);
PAINT MONO (2910 3405);
FORCEPROP 1 LASTPIN (2900 3225) $PN 2
J 0
(2910 3205);
DISPLAY 0.787234 (2910 3205);
PAINT MONO (2910 3205);
FORCEPROP 2 LAST CDS_LIB pure_quanta
J 0
(2900 3325);
DISPLAY INVISIBLE (2900 3325);
FORCEPROP 1 LAST PATH I156
J 0
(2950 3475);
DISPLAY 0.978723 (2950 3475);
PAINT WHITE (2950 3475);
DISPLAY INVISIBLE (2950 3475);
FORCEPROP 2 LAST CDS_LOCATION C1881
J 0
(2950 3525);
DISPLAY 1.021277 (2950 3525);
DISPLAY INVISIBLE (2950 3525);
FORCEPROP 2 LAST $SEC 1
J 0
(2950 3525);
DISPLAY 0.680851 (2950 3525);
PAINT MONO (2950 3525);
DISPLAY INVISIBLE (2950 3525);
FORCEPROP 2 LAST CDS_SEC 1
J 0
(2950 3525);
DISPLAY 1.021277 (2950 3525);
DISPLAY INVISIBLE (2950 3525);
FORCEADD UNIVERSAL_GND..1
(2900 3125);
FORCEPROP 3 LASTPIN (2900 3175) SIG_NAME GND\g
J 0
(2910 3185);
DISPLAY 0.659574 (2910 3185);
PAINT MONO (2910 3185);
DISPLAY INVISIBLE (2910 3185);
FORCEPROP 1 LAST HDL_POWER GND
J 1
(2925 3050);
DISPLAY 0.872340 (2925 3050);
PAINT GREEN (2925 3050);
DISPLAY INVISIBLE (2925 3050);
FORCEPROP 2 LAST CDS_LIB logical_power
J 0
(2900 3125);
DISPLAY INVISIBLE (2900 3125);
FORCEPROP 1 LAST PATH I157
J 0
(2975 3125);
DISPLAY 0.872340 (2975 3125);
PAINT AQUA (2975 3125);
DISPLAY INVISIBLE (2975 3125);
FORCEADD Q_RES..2
(2000 3950);
FORCEPROP 1 LAST PART_NUMBER CS24702JB10
J 0
(2040 3775);
DISPLAY 0.638298 (2040 3775);
DISPLAY INVISIBLE (2040 3775);
FORCEPROP 1 LAST PACK_TYPE 0402LF
J 0
(2040 3825);
DISPLAY 0.638298 (2040 3825);
FORCEPROP 1 LAST WATTAGE 1/16W
J 0
(2040 3925);
DISPLAY 0.638298 (2040 3925);
FORCEPROP 1 LAST TOLERANCE 5%
J 0
(2045 3975);
DISPLAY 0.638298 (2045 3975);
FORCEPROP 1 LAST VALUE 4.7K
J 0
(2045 4025);
DISPLAY 0.638298 (2045 4025);
FORCEPROP 1 LAST MATERIAL CHIP
J 0
(2040 3875);
DISPLAY 0.638298 (2040 3875);
FORCEPROP 1 LAST $LOCATION R3321
J 0
(2045 4075);
DISPLAY 0.978723 (2045 4075);
FORCEPROP 1 LASTPIN (2000 4050) $PN 1
J 0
(2005 4012);
DISPLAY 0.787234 (2005 4012);
PAINT MONO (2005 4012);
FORCEPROP 1 LASTPIN (2000 3850) $PN 2
J 0
(2005 3860);
DISPLAY 0.787234 (2005 3860);
PAINT MONO (2005 3860);
FORCEPROP 2 LAST CDS_LIB pure_quanta
J 0
(2000 3950);
DISPLAY INVISIBLE (2000 3950);
FORCEPROP 1 LAST PATH I158
J 0
(2050 4125);
DISPLAY 0.978723 (2050 4125);
PAINT WHITE (2050 4125);
DISPLAY INVISIBLE (2050 4125);
FORCEPROP 0 LAST CDS_LOCATION R3321
J 0
(2050 4125);
DISPLAY 1.021277 (2050 4125);
DISPLAY INVISIBLE (2050 4125);
FORCEPROP 0 LAST $SEC 1
J 0
(2050 4125);
DISPLAY 0.680851 (2050 4125);
PAINT MONO (2050 4125);
DISPLAY INVISIBLE (2050 4125);
FORCEPROP 0 LAST CDS_SEC 1
J 0
(2050 4125);
DISPLAY 1.021277 (2050 4125);
DISPLAY INVISIBLE (2050 4125);
FORCEADD MOSFET_NCH_DUAL..2
(1950 3500);
FORCEPROP 1 LAST PART_NUMBER BAM138K0003
J 0
(2101 3406);
DISPLAY 0.723404 (2101 3406);
PAINT GREEN (2101 3406);
DISPLAY INVISIBLE (2101 3406);
FORCEPROP 2 LAST PART_TYPE SMLF
J 0
(2125 3575);
DISPLAY 1.021277 (2125 3575);
FORCEPROP 2 LAST VALUE PJT138K
J 0
(2125 3525);
DISPLAY 1.021277 (2125 3525);
FORCEPROP 1 LAST MATERIAL IC
J 0
(2101 3351);
DISPLAY 0.723404 (2101 3351);
PAINT GREEN (2101 3351);
FORCEPROP 1 LAST LOCATION Q96
J 0
(2101 3476);
DISPLAY 0.723404 (2101 3476);
PAINT GREEN (2101 3476);
FORCEPROP 0 LASTPIN (2000 3700) $PN 3
R 1
J 0
(1990 3710);
DISPLAY 0.680851 (1990 3710);
PAINT MONO (1990 3710);
FORCEPROP 0 LASTPIN (1750 3450) $PN 5
J 2
(1740 3460);
DISPLAY 0.680851 (1740 3460);
PAINT MONO (1740 3460);
FORCEPROP 0 LASTPIN (2000 3300) $PN 4
R 1
J 2
(1990 3290);
DISPLAY 0.680851 (1990 3290);
PAINT MONO (1990 3290);
FORCEPROP 1 LAST CDS_LMAN_SYM_OUTLINE -150,150,150,-150
J 0
(1950 3500);
DISPLAY 0.468085 (1950 3500);
PAINT GREEN (1950 3500);
DISPLAY INVISIBLE (1950 3500);
FORCEPROP 1 LAST NEEDS_NO_SIZE TRUE
J 0
(2100 3391);
DISPLAY 0.468085 (2100 3391);
PAINT GREEN (2100 3391);
DISPLAY INVISIBLE (2100 3391);
FORCEPROP 2 LAST CDS_LIB pure_quanta
J 0
(1950 3500);
DISPLAY INVISIBLE (1950 3500);
FORCEPROP 1 LAST PATH I159
J 0
(2100 3350);
DISPLAY 0.723404 (2100 3350);
PAINT GREEN (2100 3350);
DISPLAY INVISIBLE (2100 3350);
FORCEPROP 0 LAST $SEC 2
J 0
(2125 3625);
DISPLAY 0.680851 (2125 3625);
PAINT MONO (2125 3625);
DISPLAY INVISIBLE (2125 3625);
FORCEPROP 0 LAST CDS_SEC 2
J 0
(2125 3625);
DISPLAY 1.021277 (2125 3625);
DISPLAY INVISIBLE (2125 3625);
FORCEADD UNIVERSAL_POWER..1
(-3475 6750);
FORCEPROP 3 LASTPIN (-3475 6700) SIG_NAME P3V3_AUX\g
J 0
(-3465 6710);
DISPLAY 0.659574 (-3465 6710);
PAINT MONO (-3465 6710);
DISPLAY INVISIBLE (-3465 6710);
FORCEPROP 1 LAST HDL_POWER P3V3_AUX
J 1
(-3475 6800);
DISPLAY 0.872340 (-3475 6800);
PAINT GREEN (-3475 6800);
FORCEPROP 1 LAST PATH I16
J 0
(-3425 6775);
DISPLAY 0.872340 (-3425 6775);
PAINT AQUA (-3425 6775);
DISPLAY INVISIBLE (-3425 6775);
FORCEPROP 2 LAST CDS_LIB logical_power
J 0
(-3475 6750);
PAINT MONO (-3475 6750);
DISPLAY INVISIBLE (-3475 6750);
FORCEADD UNIVERSAL_GND..1
(2000 3125);
FORCEPROP 3 LASTPIN (2000 3175) SIG_NAME GND\g
J 0
(2010 3185);
DISPLAY 0.659574 (2010 3185);
PAINT MONO (2010 3185);
DISPLAY INVISIBLE (2010 3185);
FORCEPROP 1 LAST HDL_POWER GND
J 1
(2025 3050);
DISPLAY 0.872340 (2025 3050);
PAINT GREEN (2025 3050);
DISPLAY INVISIBLE (2025 3050);
FORCEPROP 2 LAST CDS_LIB logical_power
J 0
(2000 3125);
DISPLAY INVISIBLE (2000 3125);
FORCEPROP 1 LAST PATH I160
J 0
(2075 3125);
DISPLAY 0.872340 (2075 3125);
PAINT AQUA (2075 3125);
DISPLAY INVISIBLE (2075 3125);
FORCEADD UNIVERSAL_POWER..1
(1075 4000);
FORCEPROP 3 LASTPIN (1075 3950) SIG_NAME P3V3_AUX\g
J 0
(1085 3960);
DISPLAY 0.659574 (1085 3960);
PAINT MONO (1085 3960);
DISPLAY INVISIBLE (1085 3960);
FORCEPROP 1 LAST HDL_POWER P3V3_AUX
J 1
(1075 4050);
DISPLAY 0.872340 (1075 4050);
PAINT GREEN (1075 4050);
FORCEPROP 2 LAST CDS_LIB logical_power
J 0
(1075 4000);
PAINT MONO (1075 4000);
DISPLAY INVISIBLE (1075 4000);
FORCEPROP 1 LAST PATH I161
J 0
(1125 4025);
DISPLAY 0.872340 (1125 4025);
PAINT AQUA (1125 4025);
DISPLAY INVISIBLE (1125 4025);
FORCEADD Q_RES..2
(1075 3700);
FORCEPROP 1 LAST PART_NUMBER CS24702JB10
J 0
(1115 3525);
DISPLAY 0.638298 (1115 3525);
DISPLAY INVISIBLE (1115 3525);
FORCEPROP 1 LAST TOLERANCE 5%
J 0
(1120 3725);
DISPLAY 0.638298 (1120 3725);
FORCEPROP 1 LAST PACK_TYPE 0402LF
J 0
(1115 3575);
DISPLAY 0.638298 (1115 3575);
FORCEPROP 1 LAST VALUE 4.7K
J 0
(1120 3775);
DISPLAY 0.638298 (1120 3775);
FORCEPROP 1 LAST MATERIAL CHIP
J 0
(1115 3625);
DISPLAY 0.638298 (1115 3625);
FORCEPROP 1 LAST WATTAGE 1/16W
J 0
(1115 3675);
DISPLAY 0.638298 (1115 3675);
FORCEPROP 1 LAST $LOCATION R3320
J 0
(1120 3825);
DISPLAY 0.638298 (1120 3825);
FORCEPROP 1 LASTPIN (1075 3800) $PN 1
J 0
(1080 3762);
DISPLAY 0.787234 (1080 3762);
FORCEPROP 1 LASTPIN (1075 3600) $PN 2
J 0
(1080 3610);
DISPLAY 0.787234 (1080 3610);
FORCEPROP 2 LAST CDS_LIB pure_quanta
J 0
(1075 3700);
PAINT MONO (1075 3700);
DISPLAY INVISIBLE (1075 3700);
FORCEPROP 1 LAST PATH I162
J 0
(1125 3875);
DISPLAY 0.978723 (1125 3875);
PAINT WHITE (1125 3875);
DISPLAY INVISIBLE (1125 3875);
FORCEPROP 2 LAST CDS_LOCATION R3320
J 0
(1125 3925);
DISPLAY 1.021277 (1125 3925);
DISPLAY INVISIBLE (1125 3925);
FORCEPROP 2 LAST $SEC 1
J 0
(1125 3925);
DISPLAY 0.680851 (1125 3925);
PAINT MONO (1125 3925);
DISPLAY INVISIBLE (1125 3925);
FORCEPROP 2 LAST CDS_SEC 1
J 0
(1125 3925);
DISPLAY 1.021277 (1125 3925);
DISPLAY INVISIBLE (1125 3925);
FORCEADD UNIVERSAL_GND..1
(1075 2850);
FORCEPROP 3 LASTPIN (1075 2900) SIG_NAME GND\g
J 0
(1085 2910);
DISPLAY 0.659574 (1085 2910);
PAINT MONO (1085 2910);
DISPLAY INVISIBLE (1085 2910);
FORCEPROP 2 LAST CDS_LIB logical_power
J 0
(1075 2850);
DISPLAY INVISIBLE (1075 2850);
FORCEPROP 1 LAST HDL_POWER GND
J 1
(1100 2775);
DISPLAY 0.872340 (1100 2775);
PAINT GREEN (1100 2775);
DISPLAY INVISIBLE (1100 2775);
FORCEPROP 1 LAST PATH I163
J 0
(1150 2850);
DISPLAY 0.872340 (1150 2850);
PAINT AQUA (1150 2850);
DISPLAY INVISIBLE (1150 2850);
FORCEADD UNIVERSAL_POWER..1
(-175 3700);
FORCEPROP 3 LASTPIN (-175 3650) SIG_NAME P3V3_AUX\g
J 0
(-165 3660);
DISPLAY 0.659574 (-165 3660);
PAINT MONO (-165 3660);
DISPLAY INVISIBLE (-165 3660);
FORCEPROP 1 LAST HDL_POWER P3V3_AUX
J 1
(-175 3750);
DISPLAY 0.872340 (-175 3750);
PAINT GREEN (-175 3750);
FORCEPROP 2 LAST CDS_LIB logical_power
J 0
(-175 3700);
PAINT MONO (-175 3700);
DISPLAY INVISIBLE (-175 3700);
FORCEPROP 1 LAST PATH I164
J 0
(-125 3725);
DISPLAY 0.872340 (-125 3725);
PAINT AQUA (-125 3725);
DISPLAY INVISIBLE (-125 3725);
FORCEADD UNIVERSAL_GND..1
(-150 2775);
FORCEPROP 3 LASTPIN (-150 2825) SIG_NAME GND\g
J 0
(-140 2835);
DISPLAY 0.659574 (-140 2835);
PAINT MONO (-140 2835);
DISPLAY INVISIBLE (-140 2835);
FORCEPROP 1 LAST PATH I167
J 0
(-75 2775);
DISPLAY 0.872340 (-75 2775);
PAINT AQUA (-75 2775);
DISPLAY INVISIBLE (-75 2775);
FORCEPROP 1 LAST HDL_POWER GND
J 1
(-125 2700);
DISPLAY 0.872340 (-125 2700);
PAINT GREEN (-125 2700);
DISPLAY INVISIBLE (-125 2700);
FORCEPROP 2 LAST CDS_LIB logical_power
J 0
(-150 2775);
DISPLAY INVISIBLE (-150 2775);
FORCEADD OFFPAGE..4
R 2
(-450 3175);
FORCEPROP 2 LAST $XR0 143 
J 0
(-732 3175);
DISPLAY 0.638298 (-732 3175);
PAINT MONO (-732 3175);
FORCEPROP 2 LAST CDS_LIB standard
J 0
(-450 3175);
DISPLAY INVISIBLE (-450 3175);
FORCEPROP 1 LAST COMMENT_BODY TRUE
J 2
(-425 3075);
DISPLAY 0.872340 (-425 3075);
PAINT GREEN (-425 3075);
DISPLAY INVISIBLE (-425 3075);
FORCEPROP 1 LAST OFFPAGE TRUE
J 2
(-775 3050);
DISPLAY 0.872340 (-775 3050);
PAINT GREEN (-775 3050);
DISPLAY INVISIBLE (-775 3050);
FORCEPROP 2 LAST PATH I168
J 0
(-725 3225);
DISPLAY 1.021277 (-725 3225);
DISPLAY INVISIBLE (-725 3225);
FORCEADD OFFPAGE..2
(2100 2950);
FORCEPROP 2 LAST $XR0 212 
J 0
(2289 2950);
DISPLAY 0.638298 (2289 2950);
PAINT MONO (2289 2950);
FORCEPROP 1 LAST COMMENT_BODY TRUE
J 0
(2055 2855);
DISPLAY 0.872340 (2055 2855);
PAINT GREEN (2055 2855);
DISPLAY INVISIBLE (2055 2855);
FORCEPROP 1 LAST OFFPAGE TRUE
J 0
(2425 2825);
DISPLAY 0.872340 (2425 2825);
PAINT AQUA (2425 2825);
DISPLAY INVISIBLE (2425 2825);
FORCEPROP 2 LAST PATH I169
J 0
(2275 3025);
DISPLAY 1.021277 (2275 3025);
DISPLAY INVISIBLE (2275 3025);
FORCEPROP 2 LAST CDS_LIB standard
J 0
(2100 2950);
DISPLAY INVISIBLE (2100 2950);
FORCEADD Q_RES..2
(-175 3400);
FORCEPROP 1 LAST PART_NUMBER CS41002FB09
J 0
(-135 3275);
DISPLAY 0.510638 (-135 3275);
DISPLAY INVISIBLE (-135 3275);
FORCEPROP 1 LAST PACK_TYPE 0402LF
J 0
(-135 3225);
DISPLAY 0.510638 (-135 3225);
FORCEPROP 1 LAST WATTAGE 1/16W
J 0
(-135 3375);
DISPLAY 0.510638 (-135 3375);
FORCEPROP 1 LAST TOLERANCE 1%
J 0
(-130 3425);
DISPLAY 0.510638 (-130 3425);
FORCEPROP 1 LAST MATERIAL EMPTY
J 0
(-135 3325);
DISPLAY 0.510638 (-135 3325);
FORCEPROP 1 LAST VALUE 100K
J 0
(-130 3475);
DISPLAY 0.510638 (-130 3475);
FORCEPROP 1 LAST $LOCATION R3318
J 0
(-130 3525);
DISPLAY 0.978723 (-130 3525);
FORCEPROP 1 LASTPIN (-175 3500) $PN 1
J 0
(-170 3462);
DISPLAY 0.787234 (-170 3462);
PAINT MONO (-170 3462);
FORCEPROP 1 LASTPIN (-175 3300) $PN 2
J 0
(-170 3310);
DISPLAY 0.787234 (-170 3310);
PAINT MONO (-170 3310);
FORCEPROP 2 LAST CDS_LIB pure_quanta
J 0
(-175 3400);
DISPLAY INVISIBLE (-175 3400);
FORCEPROP 1 LAST PATH I171
J 0
(-125 3575);
DISPLAY 0.978723 (-125 3575);
PAINT WHITE (-125 3575);
DISPLAY INVISIBLE (-125 3575);
FORCEPROP 0 LAST CDS_LOCATION R3318
J 0
(-125 3575);
DISPLAY 1.021277 (-125 3575);
DISPLAY INVISIBLE (-125 3575);
FORCEPROP 0 LAST $SEC 1
J 0
(-125 3575);
DISPLAY 0.680851 (-125 3575);
PAINT MONO (-125 3575);
DISPLAY INVISIBLE (-125 3575);
FORCEPROP 0 LAST CDS_SEC 1
J 0
(-125 3575);
DISPLAY 1.021277 (-125 3575);
DISPLAY INVISIBLE (-125 3575);
FORCEADD Q_RES..2
(-150 2975);
FORCEPROP 1 LAST PART_NUMBER CS35492FB03
J 0
(-110 2850);
DISPLAY 0.787234 (-110 2850);
DISPLAY INVISIBLE (-110 2850);
FORCEPROP 1 LAST TOLERANCE 1%
J 0
(-105 3000);
DISPLAY 0.787234 (-105 3000);
FORCEPROP 1 LAST WATTAGE 1/16W
J 0
(-110 2950);
DISPLAY 0.787234 (-110 2950);
FORCEPROP 1 LAST PACK_TYPE 0402LF
J 0
(-110 2800);
DISPLAY 0.787234 (-110 2800);
FORCEPROP 1 LAST MATERIAL CHIP
J 0
(-110 2900);
DISPLAY 0.787234 (-110 2900);
FORCEPROP 1 LAST VALUE 54.9K
J 0
(-105 3050);
DISPLAY 0.787234 (-105 3050);
FORCEPROP 1 LAST $LOCATION R3511
J 0
(-105 3100);
DISPLAY 0.978723 (-105 3100);
FORCEPROP 1 LASTPIN (-150 3075) $PN 1
J 0
(-145 3037);
DISPLAY 0.787234 (-145 3037);
PAINT MONO (-145 3037);
FORCEPROP 1 LASTPIN (-150 2875) $PN 2
J 0
(-145 2885);
DISPLAY 0.787234 (-145 2885);
PAINT MONO (-145 2885);
FORCEPROP 2 LAST CDS_LIB pure_quanta
J 0
(-150 2975);
DISPLAY INVISIBLE (-150 2975);
FORCEPROP 1 LAST PATH I172
J 0
(-100 3150);
DISPLAY 0.978723 (-100 3150);
PAINT WHITE (-100 3150);
DISPLAY INVISIBLE (-100 3150);
FORCEPROP 0 LAST CDS_LOCATION R3511
J 0
(-100 3150);
DISPLAY 1.021277 (-100 3150);
DISPLAY INVISIBLE (-100 3150);
FORCEPROP 0 LAST $SEC 1
J 0
(-100 3150);
DISPLAY 0.680851 (-100 3150);
PAINT MONO (-100 3150);
DISPLAY INVISIBLE (-100 3150);
FORCEPROP 0 LAST CDS_SEC 1
J 0
(-100 3150);
DISPLAY 1.021277 (-100 3150);
DISPLAY INVISIBLE (-100 3150);
FORCEADD Q_RES..2
(-125 5900);
FORCEPROP 1 LAST PART_NUMBER CS35492FB03
J 0
(-85 5775);
DISPLAY 0.787234 (-85 5775);
DISPLAY INVISIBLE (-85 5775);
FORCEPROP 1 LAST VALUE 54.9K
J 0
(-80 5975);
DISPLAY 0.787234 (-80 5975);
FORCEPROP 1 LAST TOLERANCE 1%
J 0
(-80 5925);
DISPLAY 0.787234 (-80 5925);
FORCEPROP 1 LAST WATTAGE 1/16W
J 0
(-85 5875);
DISPLAY 0.787234 (-85 5875);
FORCEPROP 1 LAST MATERIAL CHIP
J 0
(-85 5825);
DISPLAY 0.787234 (-85 5825);
FORCEPROP 1 LAST PACK_TYPE 0402LF
J 0
(-85 5725);
DISPLAY 0.787234 (-85 5725);
FORCEPROP 1 LAST $LOCATION R3513
J 0
(-80 6025);
DISPLAY 0.978723 (-80 6025);
FORCEPROP 1 LASTPIN (-125 6000) $PN 1
J 0
(-120 5962);
DISPLAY 0.787234 (-120 5962);
PAINT MONO (-120 5962);
FORCEPROP 1 LASTPIN (-125 5800) $PN 2
J 0
(-120 5810);
DISPLAY 0.787234 (-120 5810);
PAINT MONO (-120 5810);
FORCEPROP 1 LAST PATH I173
J 0
(-75 6075);
DISPLAY 0.978723 (-75 6075);
PAINT WHITE (-75 6075);
DISPLAY INVISIBLE (-75 6075);
FORCEPROP 2 LAST CDS_LIB pure_quanta
J 0
(-125 5900);
DISPLAY INVISIBLE (-125 5900);
FORCEPROP 0 LAST CDS_LOCATION R3513
J 0
(-75 6075);
DISPLAY 1.021277 (-75 6075);
DISPLAY INVISIBLE (-75 6075);
FORCEPROP 0 LAST $SEC 1
J 0
(-75 6075);
DISPLAY 0.680851 (-75 6075);
PAINT MONO (-75 6075);
DISPLAY INVISIBLE (-75 6075);
FORCEPROP 0 LAST CDS_SEC 1
J 0
(-75 6075);
DISPLAY 1.021277 (-75 6075);
DISPLAY INVISIBLE (-75 6075);
FORCEADD Q_RES..2
(-150 6325);
FORCEPROP 1 LAST PART_NUMBER CS41002FB09
J 0
(-110 6200);
DISPLAY 0.510638 (-110 6200);
DISPLAY INVISIBLE (-110 6200);
FORCEPROP 1 LAST WATTAGE 1/16W
J 0
(-110 6300);
DISPLAY 0.510638 (-110 6300);
FORCEPROP 1 LAST PACK_TYPE 0402LF
J 0
(-110 6150);
DISPLAY 0.510638 (-110 6150);
FORCEPROP 1 LAST MATERIAL EMPTY
J 0
(-110 6250);
DISPLAY 0.510638 (-110 6250);
FORCEPROP 1 LAST VALUE 100K
J 0
(-105 6400);
DISPLAY 0.510638 (-105 6400);
FORCEPROP 1 LAST TOLERANCE 1%
J 0
(-105 6350);
DISPLAY 0.510638 (-105 6350);
FORCEPROP 1 LAST $LOCATION R3512
J 0
(-105 6450);
DISPLAY 0.978723 (-105 6450);
FORCEPROP 1 LASTPIN (-150 6425) $PN 1
J 0
(-145 6387);
DISPLAY 0.787234 (-145 6387);
PAINT MONO (-145 6387);
FORCEPROP 1 LASTPIN (-150 6225) $PN 2
J 0
(-145 6235);
DISPLAY 0.787234 (-145 6235);
PAINT MONO (-145 6235);
FORCEPROP 2 LAST CDS_LIB pure_quanta
J 0
(-150 6325);
DISPLAY INVISIBLE (-150 6325);
FORCEPROP 1 LAST PATH I174
J 0
(-100 6500);
DISPLAY 0.978723 (-100 6500);
PAINT WHITE (-100 6500);
DISPLAY INVISIBLE (-100 6500);
FORCEPROP 0 LAST CDS_LOCATION R3512
J 0
(-100 6500);
DISPLAY 1.021277 (-100 6500);
DISPLAY INVISIBLE (-100 6500);
FORCEPROP 0 LAST $SEC 1
J 0
(-100 6500);
DISPLAY 0.680851 (-100 6500);
PAINT MONO (-100 6500);
DISPLAY INVISIBLE (-100 6500);
FORCEPROP 0 LAST CDS_SEC 1
J 0
(-100 6500);
DISPLAY 1.021277 (-100 6500);
DISPLAY INVISIBLE (-100 6500);
FORCEADD Q_RES..2
(-125 4950);
FORCEPROP 1 LAST PART_NUMBER CS35492FB03
J 0
(-85 4825);
DISPLAY 0.787234 (-85 4825);
DISPLAY INVISIBLE (-85 4825);
FORCEPROP 1 LAST TOLERANCE 1%
J 0
(-80 4975);
DISPLAY 0.787234 (-80 4975);
FORCEPROP 1 LAST VALUE 54.9K
J 0
(-80 5025);
DISPLAY 0.787234 (-80 5025);
FORCEPROP 1 LAST WATTAGE 1/16W
J 0
(-85 4925);
DISPLAY 0.787234 (-85 4925);
FORCEPROP 1 LAST MATERIAL CHIP
J 0
(-85 4875);
DISPLAY 0.787234 (-85 4875);
FORCEPROP 1 LAST PACK_TYPE 0402LF
J 0
(-85 4775);
DISPLAY 0.787234 (-85 4775);
FORCEPROP 1 LAST $LOCATION R3514
J 0
(-80 5075);
DISPLAY 0.978723 (-80 5075);
FORCEPROP 1 LASTPIN (-125 5050) $PN 1
J 0
(-120 5012);
DISPLAY 0.787234 (-120 5012);
PAINT MONO (-120 5012);
FORCEPROP 1 LASTPIN (-125 4850) $PN 2
J 0
(-120 4860);
DISPLAY 0.787234 (-120 4860);
PAINT MONO (-120 4860);
FORCEPROP 2 LAST CDS_LIB pure_quanta
J 0
(-125 4950);
DISPLAY INVISIBLE (-125 4950);
FORCEPROP 1 LAST PATH I175
J 0
(-75 5125);
DISPLAY 0.978723 (-75 5125);
PAINT WHITE (-75 5125);
DISPLAY INVISIBLE (-75 5125);
FORCEPROP 0 LAST CDS_LOCATION R3514
J 0
(-75 5125);
DISPLAY 1.021277 (-75 5125);
DISPLAY INVISIBLE (-75 5125);
FORCEPROP 0 LAST $SEC 1
J 0
(-75 5125);
DISPLAY 0.680851 (-75 5125);
PAINT MONO (-75 5125);
DISPLAY INVISIBLE (-75 5125);
FORCEPROP 0 LAST CDS_SEC 1
J 0
(-75 5125);
DISPLAY 1.021277 (-75 5125);
DISPLAY INVISIBLE (-75 5125);
FORCEADD Q_RES..2
(-4675 3250);
FORCEPROP 1 LAST PART_NUMBER CS35492FB03
J 0
(-4635 3125);
DISPLAY 0.787234 (-4635 3125);
DISPLAY INVISIBLE (-4635 3125);
FORCEPROP 1 LAST PACK_TYPE 0402LF
J 0
(-4635 3075);
DISPLAY 0.787234 (-4635 3075);
FORCEPROP 1 LAST MATERIAL CHIP
J 0
(-4635 3175);
DISPLAY 0.787234 (-4635 3175);
FORCEPROP 1 LAST WATTAGE 1/16W
J 0
(-4635 3225);
DISPLAY 0.787234 (-4635 3225);
FORCEPROP 1 LAST VALUE 54.9K
J 0
(-4630 3325);
DISPLAY 0.787234 (-4630 3325);
FORCEPROP 1 LAST TOLERANCE 1%
J 0
(-4630 3275);
DISPLAY 0.787234 (-4630 3275);
FORCEPROP 1 LAST $LOCATION R3510
J 0
(-4630 3375);
DISPLAY 0.978723 (-4630 3375);
FORCEPROP 1 LASTPIN (-4675 3350) $PN 1
J 0
(-4670 3312);
DISPLAY 0.787234 (-4670 3312);
PAINT MONO (-4670 3312);
FORCEPROP 1 LASTPIN (-4675 3150) $PN 2
J 0
(-4670 3160);
DISPLAY 0.787234 (-4670 3160);
PAINT MONO (-4670 3160);
FORCEPROP 2 LAST CDS_LIB pure_quanta
J 0
(-4675 3250);
DISPLAY INVISIBLE (-4675 3250);
FORCEPROP 1 LAST PATH I176
J 0
(-4625 3425);
DISPLAY 0.978723 (-4625 3425);
PAINT WHITE (-4625 3425);
DISPLAY INVISIBLE (-4625 3425);
FORCEPROP 0 LAST CDS_LOCATION R3510
J 0
(-4625 3425);
DISPLAY 1.021277 (-4625 3425);
DISPLAY INVISIBLE (-4625 3425);
FORCEPROP 0 LAST $SEC 1
J 0
(-4625 3425);
DISPLAY 0.680851 (-4625 3425);
PAINT MONO (-4625 3425);
DISPLAY INVISIBLE (-4625 3425);
FORCEPROP 0 LAST CDS_SEC 1
J 0
(-4625 3425);
DISPLAY 1.021277 (-4625 3425);
DISPLAY INVISIBLE (-4625 3425);
FORCEADD Q_RES..2
(-3475 6450);
FORCEPROP 1 LAST PART_NUMBER CS24702JB10
J 0
(-3435 6275);
DISPLAY 0.638298 (-3435 6275);
DISPLAY INVISIBLE (-3435 6275);
FORCEPROP 1 LAST MATERIAL CHIP
J 0
(-3435 6375);
DISPLAY 0.638298 (-3435 6375);
FORCEPROP 1 LAST VALUE 4.7K
J 0
(-3430 6525);
DISPLAY 0.638298 (-3430 6525);
FORCEPROP 1 LAST PACK_TYPE 0402LF
J 0
(-3435 6325);
DISPLAY 0.638298 (-3435 6325);
FORCEPROP 1 LAST TOLERANCE 5%
J 0
(-3430 6475);
DISPLAY 0.638298 (-3430 6475);
FORCEPROP 1 LAST WATTAGE 1/16W
J 0
(-3435 6425);
DISPLAY 0.638298 (-3435 6425);
FORCEPROP 1 LAST $LOCATION R2834
J 0
(-3430 6575);
DISPLAY 0.638298 (-3430 6575);
FORCEPROP 1 LASTPIN (-3475 6550) $PN 1
J 0
(-3470 6512);
DISPLAY 0.787234 (-3470 6512);
FORCEPROP 1 LASTPIN (-3475 6350) $PN 2
J 0
(-3470 6360);
DISPLAY 0.787234 (-3470 6360);
FORCEPROP 1 LAST PATH I18
J 0
(-3425 6625);
DISPLAY 0.978723 (-3425 6625);
PAINT WHITE (-3425 6625);
DISPLAY INVISIBLE (-3425 6625);
FORCEPROP 2 LAST CDS_LIB pure_quanta
J 0
(-3475 6450);
PAINT MONO (-3475 6450);
DISPLAY INVISIBLE (-3475 6450);
FORCEPROP 2 LAST CDS_LOCATION R2834
J 0
(-3425 6675);
DISPLAY 1.021277 (-3425 6675);
DISPLAY INVISIBLE (-3425 6675);
FORCEPROP 2 LAST $SEC 1
J 0
(-3425 6675);
DISPLAY 0.680851 (-3425 6675);
PAINT MONO (-3425 6675);
DISPLAY INVISIBLE (-3425 6675);
FORCEPROP 2 LAST CDS_SEC 1
J 0
(-3425 6675);
DISPLAY 1.021277 (-3425 6675);
DISPLAY INVISIBLE (-3425 6675);
FORCEADD Q_RES..2
(-3450 5100);
FORCEPROP 1 LAST PART_NUMBER CS24702JB10
J 0
(-3410 4925);
DISPLAY 0.638298 (-3410 4925);
DISPLAY INVISIBLE (-3410 4925);
FORCEPROP 1 LAST PACK_TYPE 0402LF
J 0
(-3410 4975);
DISPLAY 0.638298 (-3410 4975);
FORCEPROP 1 LAST MATERIAL CHIP
J 0
(-3410 5025);
DISPLAY 0.638298 (-3410 5025);
FORCEPROP 1 LAST WATTAGE 1/16W
J 0
(-3410 5075);
DISPLAY 0.638298 (-3410 5075);
FORCEPROP 1 LAST TOLERANCE 5%
J 0
(-3405 5125);
DISPLAY 0.638298 (-3405 5125);
FORCEPROP 1 LAST VALUE 4.7K
J 0
(-3405 5175);
DISPLAY 0.638298 (-3405 5175);
FORCEPROP 1 LAST $LOCATION R2836
J 0
(-3405 5225);
DISPLAY 0.638298 (-3405 5225);
FORCEPROP 1 LASTPIN (-3450 5200) $PN 1
J 0
(-3445 5162);
DISPLAY 0.787234 (-3445 5162);
FORCEPROP 1 LASTPIN (-3450 5000) $PN 2
J 0
(-3445 5010);
DISPLAY 0.787234 (-3445 5010);
FORCEPROP 1 LAST PATH I19
J 0
(-3400 5275);
DISPLAY 0.978723 (-3400 5275);
PAINT WHITE (-3400 5275);
DISPLAY INVISIBLE (-3400 5275);
FORCEPROP 2 LAST CDS_LIB pure_quanta
J 0
(-3450 5100);
PAINT MONO (-3450 5100);
DISPLAY INVISIBLE (-3450 5100);
FORCEPROP 2 LAST CDS_LOCATION R2836
J 0
(-3400 5325);
DISPLAY 1.021277 (-3400 5325);
DISPLAY INVISIBLE (-3400 5325);
FORCEPROP 2 LAST $SEC 1
J 0
(-3400 5325);
DISPLAY 0.680851 (-3400 5325);
PAINT MONO (-3400 5325);
DISPLAY INVISIBLE (-3400 5325);
FORCEPROP 2 LAST CDS_SEC 1
J 0
(-3400 5325);
DISPLAY 1.021277 (-3400 5325);
DISPLAY INVISIBLE (-3400 5325);
FORCEADD UNIVERSAL_POWER..1
(-3450 5400);
FORCEPROP 3 LASTPIN (-3450 5350) SIG_NAME P3V3_AUX\g
J 0
(-3440 5360);
DISPLAY 0.659574 (-3440 5360);
PAINT MONO (-3440 5360);
DISPLAY INVISIBLE (-3440 5360);
FORCEPROP 1 LAST HDL_POWER P3V3_AUX
J 1
(-3450 5450);
DISPLAY 0.872340 (-3450 5450);
PAINT GREEN (-3450 5450);
FORCEPROP 1 LAST PATH I21
J 0
(-3400 5425);
DISPLAY 0.872340 (-3400 5425);
PAINT AQUA (-3400 5425);
DISPLAY INVISIBLE (-3400 5425);
FORCEPROP 2 LAST CDS_LIB logical_power
J 0
(-3450 5400);
PAINT MONO (-3450 5400);
DISPLAY INVISIBLE (-3450 5400);
FORCEADD OFFPAGE..4
R 2
(-425 7475);
FORCEPROP 2 LAST $XR0 137 
J 0
(-677 7475);
DISPLAY 0.638298 (-677 7475);
PAINT MONO (-677 7475);
FORCEPROP 1 LAST OFFPAGE TRUE
J 2
(-750 7350);
DISPLAY 0.872340 (-750 7350);
PAINT GREEN (-750 7350);
DISPLAY INVISIBLE (-750 7350);
FORCEPROP 1 LAST COMMENT_BODY TRUE
J 2
(-400 7375);
DISPLAY 0.872340 (-400 7375);
PAINT GREEN (-400 7375);
DISPLAY INVISIBLE (-400 7375);
FORCEPROP 2 LAST CDS_LIB standard
J 0
(-425 7475);
DISPLAY INVISIBLE (-425 7475);
FORCEPROP 2 LAST PATH I22
J 0
(-600 7525);
DISPLAY 1.021277 (-600 7525);
DISPLAY INVISIBLE (-600 7525);
FORCEADD UNIVERSAL_GND..1
(1100 7150);
FORCEPROP 3 LASTPIN (1100 7200) SIG_NAME GND\g
J 0
(1110 7210);
DISPLAY 0.659574 (1110 7210);
PAINT MONO (1110 7210);
DISPLAY INVISIBLE (1110 7210);
FORCEPROP 1 LAST HDL_POWER GND
J 1
(1125 7075);
DISPLAY 0.872340 (1125 7075);
PAINT GREEN (1125 7075);
DISPLAY INVISIBLE (1125 7075);
FORCEPROP 1 LAST PATH I23
J 0
(1175 7150);
DISPLAY 0.872340 (1175 7150);
PAINT AQUA (1175 7150);
DISPLAY INVISIBLE (1175 7150);
FORCEPROP 2 LAST CDS_LIB logical_power
J 0
(1100 7150);
DISPLAY INVISIBLE (1100 7150);
FORCEADD Q_RES..2
(1100 7925);
FORCEPROP 1 LAST PART_NUMBER CS24702JB10
J 0
(1140 7750);
DISPLAY 0.638298 (1140 7750);
DISPLAY INVISIBLE (1140 7750);
FORCEPROP 1 LAST PACK_TYPE 0402LF
J 0
(1140 7800);
DISPLAY 0.638298 (1140 7800);
FORCEPROP 1 LAST WATTAGE 1/16W
J 0
(1140 7900);
DISPLAY 0.638298 (1140 7900);
FORCEPROP 1 LAST MATERIAL CHIP
J 0
(1140 7850);
DISPLAY 0.638298 (1140 7850);
FORCEPROP 1 LAST TOLERANCE 5%
J 0
(1145 7950);
DISPLAY 0.638298 (1145 7950);
FORCEPROP 1 LAST VALUE 4.7K
J 0
(1145 8000);
DISPLAY 0.638298 (1145 8000);
FORCEPROP 1 LAST $LOCATION R2841
J 0
(1145 8050);
DISPLAY 0.638298 (1145 8050);
FORCEPROP 1 LASTPIN (1100 8025) $PN 1
J 0
(1105 7987);
DISPLAY 0.787234 (1105 7987);
FORCEPROP 1 LASTPIN (1100 7825) $PN 2
J 0
(1105 7835);
DISPLAY 0.787234 (1105 7835);
FORCEPROP 1 LAST PATH I24
J 0
(1150 8100);
DISPLAY 0.978723 (1150 8100);
PAINT WHITE (1150 8100);
DISPLAY INVISIBLE (1150 8100);
FORCEPROP 2 LAST CDS_LIB pure_quanta
J 0
(1100 7925);
PAINT MONO (1100 7925);
DISPLAY INVISIBLE (1100 7925);
FORCEPROP 2 LAST CDS_LOCATION R2841
J 0
(1150 8150);
DISPLAY 1.021277 (1150 8150);
DISPLAY INVISIBLE (1150 8150);
FORCEPROP 2 LAST $SEC 1
J 0
(1150 8150);
DISPLAY 0.680851 (1150 8150);
PAINT MONO (1150 8150);
DISPLAY INVISIBLE (1150 8150);
FORCEPROP 2 LAST CDS_SEC 1
J 0
(1150 8150);
DISPLAY 1.021277 (1150 8150);
DISPLAY INVISIBLE (1150 8150);
FORCEADD UNIVERSAL_POWER..1
(1100 8225);
FORCEPROP 3 LASTPIN (1100 8175) SIG_NAME P3V3_AUX\g
J 0
(1110 8185);
DISPLAY 0.659574 (1110 8185);
PAINT MONO (1110 8185);
DISPLAY INVISIBLE (1110 8185);
FORCEPROP 1 LAST HDL_POWER P3V3_AUX
J 1
(1100 8275);
DISPLAY 0.872340 (1100 8275);
PAINT GREEN (1100 8275);
FORCEPROP 1 LAST PATH I25
J 0
(1150 8250);
DISPLAY 0.872340 (1150 8250);
PAINT AQUA (1150 8250);
DISPLAY INVISIBLE (1150 8250);
FORCEPROP 2 LAST CDS_LIB logical_power
J 0
(1100 8225);
PAINT MONO (1100 8225);
DISPLAY INVISIBLE (1100 8225);
FORCEADD OFFPAGE..4
R 2
(-425 6100);
FORCEPROP 2 LAST $XR0 142 
J 0
(-677 6100);
DISPLAY 0.638298 (-677 6100);
PAINT MONO (-677 6100);
FORCEPROP 2 LAST PATH I28
J 0
(-600 6150);
DISPLAY 1.021277 (-600 6150);
DISPLAY INVISIBLE (-600 6150);
FORCEPROP 1 LAST OFFPAGE TRUE
J 2
(-750 5975);
DISPLAY 0.872340 (-750 5975);
PAINT GREEN (-750 5975);
DISPLAY INVISIBLE (-750 5975);
FORCEPROP 1 LAST COMMENT_BODY TRUE
J 2
(-400 6000);
DISPLAY 0.872340 (-400 6000);
PAINT GREEN (-400 6000);
DISPLAY INVISIBLE (-400 6000);
FORCEPROP 2 LAST CDS_LIB standard
J 0
(-425 6100);
DISPLAY INVISIBLE (-425 6100);
FORCEADD UNIVERSAL_GND..1
(1100 5775);
FORCEPROP 3 LASTPIN (1100 5825) SIG_NAME GND\g
J 0
(1110 5835);
DISPLAY 0.659574 (1110 5835);
PAINT MONO (1110 5835);
DISPLAY INVISIBLE (1110 5835);
FORCEPROP 1 LAST PATH I29
J 0
(1175 5775);
DISPLAY 0.872340 (1175 5775);
PAINT AQUA (1175 5775);
DISPLAY INVISIBLE (1175 5775);
FORCEPROP 2 LAST CDS_LIB logical_power
J 0
(1100 5775);
DISPLAY INVISIBLE (1100 5775);
FORCEPROP 1 LAST HDL_POWER GND
J 1
(1125 5700);
DISPLAY 0.872340 (1125 5700);
PAINT GREEN (1125 5700);
DISPLAY INVISIBLE (1125 5700);
FORCEADD Q_RES..2
(1100 6625);
FORCEPROP 1 LAST PART_NUMBER CS24702JB10
J 0
(1140 6450);
DISPLAY 0.638298 (1140 6450);
DISPLAY INVISIBLE (1140 6450);
FORCEPROP 1 LAST WATTAGE 1/16W
J 0
(1140 6600);
DISPLAY 0.638298 (1140 6600);
FORCEPROP 1 LAST MATERIAL CHIP
J 0
(1140 6550);
DISPLAY 0.638298 (1140 6550);
FORCEPROP 1 LAST PACK_TYPE 0402LF
J 0
(1140 6500);
DISPLAY 0.638298 (1140 6500);
FORCEPROP 1 LAST TOLERANCE 5%
J 0
(1145 6650);
DISPLAY 0.638298 (1145 6650);
FORCEPROP 1 LAST VALUE 4.7K
J 0
(1145 6700);
DISPLAY 0.638298 (1145 6700);
FORCEPROP 1 LAST $LOCATION R2842
J 0
(1145 6750);
DISPLAY 0.638298 (1145 6750);
FORCEPROP 1 LASTPIN (1100 6725) $PN 1
J 0
(1105 6687);
DISPLAY 0.787234 (1105 6687);
FORCEPROP 1 LASTPIN (1100 6525) $PN 2
J 0
(1105 6535);
DISPLAY 0.787234 (1105 6535);
FORCEPROP 1 LAST PATH I30
J 0
(1150 6800);
DISPLAY 0.978723 (1150 6800);
PAINT WHITE (1150 6800);
DISPLAY INVISIBLE (1150 6800);
FORCEPROP 2 LAST CDS_LIB pure_quanta
J 0
(1100 6625);
PAINT MONO (1100 6625);
DISPLAY INVISIBLE (1100 6625);
FORCEPROP 2 LAST CDS_LOCATION R2842
J 0
(1150 6850);
DISPLAY 1.021277 (1150 6850);
DISPLAY INVISIBLE (1150 6850);
FORCEPROP 2 LAST $SEC 1
J 0
(1150 6850);
DISPLAY 0.680851 (1150 6850);
PAINT MONO (1150 6850);
DISPLAY INVISIBLE (1150 6850);
FORCEPROP 2 LAST CDS_SEC 1
J 0
(1150 6850);
DISPLAY 1.021277 (1150 6850);
DISPLAY INVISIBLE (1150 6850);
FORCEADD UNIVERSAL_POWER..1
(1100 6925);
FORCEPROP 3 LASTPIN (1100 6875) SIG_NAME P3V3_AUX\g
J 0
(1110 6885);
DISPLAY 0.659574 (1110 6885);
PAINT MONO (1110 6885);
DISPLAY INVISIBLE (1110 6885);
FORCEPROP 1 LAST HDL_POWER P3V3_AUX
J 1
(1100 6975);
DISPLAY 0.872340 (1100 6975);
PAINT GREEN (1100 6975);
FORCEPROP 1 LAST PATH I31
J 0
(1150 6950);
DISPLAY 0.872340 (1150 6950);
PAINT AQUA (1150 6950);
DISPLAY INVISIBLE (1150 6950);
FORCEPROP 2 LAST CDS_LIB logical_power
J 0
(1100 6925);
PAINT MONO (1100 6925);
DISPLAY INVISIBLE (1100 6925);
FORCEADD MOSFET_NCH_DUAL..1
(-3575 7400);
FORCEPROP 1 LAST PART_NUMBER BAM138K0003
J 0
(-3424 7314);
DISPLAY 0.723404 (-3424 7314);
PAINT GREEN (-3424 7314);
DISPLAY INVISIBLE (-3424 7314);
FORCEPROP 2 LAST VALUE PJT138K
J 0
(-3400 7425);
DISPLAY 1.021277 (-3400 7425);
FORCEPROP 1 LAST MATERIAL IC
J 0
(-3424 7249);
DISPLAY 0.723404 (-3424 7249);
PAINT GREEN (-3424 7249);
FORCEPROP 2 LAST PART_TYPE SMLF
J 0
(-3400 7475);
DISPLAY 1.021277 (-3400 7475);
FORCEPROP 1 LAST $LOCATION Q67
J 0
(-3424 7374);
DISPLAY 0.723404 (-3424 7374);
PAINT GREEN (-3424 7374);
FORCEPROP 0 LASTPIN (-3525 7600) $PN 6
R 1
J 0
(-3535 7610);
DISPLAY 0.680851 (-3535 7610);
PAINT MONO (-3535 7610);
FORCEPROP 0 LASTPIN (-3775 7350) $PN 2
J 2
(-3785 7360);
DISPLAY 0.680851 (-3785 7360);
PAINT MONO (-3785 7360);
FORCEPROP 0 LASTPIN (-3525 7200) $PN 1
R 1
J 2
(-3535 7190);
DISPLAY 0.680851 (-3535 7190);
PAINT MONO (-3535 7190);
FORCEPROP 1 LAST CDS_LMAN_SYM_OUTLINE -150,150,150,-150
J 0
(-3575 7400);
DISPLAY 0.468085 (-3575 7400);
PAINT GREEN (-3575 7400);
DISPLAY INVISIBLE (-3575 7400);
FORCEPROP 1 LAST PATH I33
J 0
(-3575 7400);
DISPLAY 0.723404 (-3575 7400);
PAINT GREEN (-3575 7400);
DISPLAY INVISIBLE (-3575 7400);
FORCEPROP 1 LAST NEEDS_NO_SIZE TRUE
J 0
(-3575 7399);
DISPLAY 0.468085 (-3575 7399);
PAINT GREEN (-3575 7399);
DISPLAY INVISIBLE (-3575 7399);
FORCEPROP 2 LAST CDS_LIB pure_quanta
J 0
(-3575 7400);
DISPLAY INVISIBLE (-3575 7400);
FORCEPROP 2 LAST CDS_LOCATION Q67
J 0
(-3400 7525);
DISPLAY 1.021277 (-3400 7525);
DISPLAY INVISIBLE (-3400 7525);
FORCEPROP 0 LAST $SEC 1
J 0
(-3400 7525);
DISPLAY 0.680851 (-3400 7525);
PAINT MONO (-3400 7525);
DISPLAY INVISIBLE (-3400 7525);
FORCEPROP 2 LAST CDS_SEC 1
J 0
(-3400 7525);
DISPLAY 1.021277 (-3400 7525);
DISPLAY INVISIBLE (-3400 7525);
FORCEADD MOSFET_NCH_DUAL..1
(-3500 4650);
FORCEPROP 1 LAST PART_NUMBER BAM138K0003
J 0
(-3349 4564);
DISPLAY 0.723404 (-3349 4564);
PAINT GREEN (-3349 4564);
DISPLAY INVISIBLE (-3349 4564);
FORCEPROP 2 LAST PART_TYPE SMLF
J 0
(-3325 4725);
DISPLAY 1.021277 (-3325 4725);
FORCEPROP 2 LAST VALUE PJT138K
J 0
(-3325 4675);
DISPLAY 1.021277 (-3325 4675);
FORCEPROP 1 LAST MATERIAL IC
J 0
(-3349 4499);
DISPLAY 0.723404 (-3349 4499);
PAINT GREEN (-3349 4499);
FORCEPROP 1 LAST LOCATION Q70
J 0
(-3349 4624);
DISPLAY 0.723404 (-3349 4624);
PAINT GREEN (-3349 4624);
FORCEPROP 0 LASTPIN (-3450 4850) $PN 6
R 1
J 0
(-3460 4860);
DISPLAY 0.680851 (-3460 4860);
PAINT MONO (-3460 4860);
FORCEPROP 0 LASTPIN (-3700 4600) $PN 2
J 2
(-3710 4610);
DISPLAY 0.680851 (-3710 4610);
PAINT MONO (-3710 4610);
FORCEPROP 0 LASTPIN (-3450 4450) $PN 1
R 1
J 2
(-3460 4440);
DISPLAY 0.680851 (-3460 4440);
PAINT MONO (-3460 4440);
FORCEPROP 1 LAST CDS_LMAN_SYM_OUTLINE -150,150,150,-150
J 0
(-3500 4650);
DISPLAY 0.468085 (-3500 4650);
PAINT GREEN (-3500 4650);
DISPLAY INVISIBLE (-3500 4650);
FORCEPROP 1 LAST PATH I35
J 0
(-3500 4650);
DISPLAY 0.723404 (-3500 4650);
PAINT GREEN (-3500 4650);
DISPLAY INVISIBLE (-3500 4650);
FORCEPROP 1 LAST NEEDS_NO_SIZE TRUE
J 0
(-3500 4649);
DISPLAY 0.468085 (-3500 4649);
PAINT GREEN (-3500 4649);
DISPLAY INVISIBLE (-3500 4649);
FORCEPROP 2 LAST CDS_LIB pure_quanta
J 0
(-3500 4650);
DISPLAY INVISIBLE (-3500 4650);
FORCEPROP 0 LAST $SEC 1
J 0
(-3325 4775);
DISPLAY 0.680851 (-3325 4775);
PAINT MONO (-3325 4775);
DISPLAY INVISIBLE (-3325 4775);
FORCEPROP 2 LAST CDS_SEC 1
J 0
(-3325 4775);
DISPLAY 1.021277 (-3325 4775);
DISPLAY INVISIBLE (-3325 4775);
FORCEADD MOSFET_NCH_DUAL..1
(1050 6150);
FORCEPROP 1 LAST PART_NUMBER BAM138K0003
J 0
(1201 6064);
DISPLAY 0.723404 (1201 6064);
PAINT GREEN (1201 6064);
DISPLAY INVISIBLE (1201 6064);
FORCEPROP 2 LAST PART_TYPE SMLF
J 0
(1225 6225);
DISPLAY 1.021277 (1225 6225);
FORCEPROP 2 LAST VALUE PJT138K
J 0
(1225 6175);
DISPLAY 1.021277 (1225 6175);
FORCEPROP 1 LAST MATERIAL IC
J 0
(1201 5999);
DISPLAY 0.723404 (1201 5999);
PAINT GREEN (1201 5999);
FORCEPROP 1 LAST LOCATION Q72
J 0
(1201 6124);
DISPLAY 0.723404 (1201 6124);
PAINT GREEN (1201 6124);
FORCEPROP 0 LASTPIN (1100 6350) $PN 6
R 1
J 0
(1090 6360);
DISPLAY 0.680851 (1090 6360);
PAINT MONO (1090 6360);
FORCEPROP 0 LASTPIN (850 6100) $PN 2
J 2
(840 6110);
DISPLAY 0.680851 (840 6110);
PAINT MONO (840 6110);
FORCEPROP 0 LASTPIN (1100 5950) $PN 1
R 1
J 2
(1090 5940);
DISPLAY 0.680851 (1090 5940);
PAINT MONO (1090 5940);
FORCEPROP 1 LAST CDS_LMAN_SYM_OUTLINE -150,150,150,-150
J 0
(1050 6150);
DISPLAY 0.468085 (1050 6150);
PAINT GREEN (1050 6150);
DISPLAY INVISIBLE (1050 6150);
FORCEPROP 1 LAST PATH I37
J 0
(1050 6150);
DISPLAY 0.723404 (1050 6150);
PAINT GREEN (1050 6150);
DISPLAY INVISIBLE (1050 6150);
FORCEPROP 1 LAST NEEDS_NO_SIZE TRUE
J 0
(1050 6149);
DISPLAY 0.468085 (1050 6149);
PAINT GREEN (1050 6149);
DISPLAY INVISIBLE (1050 6149);
FORCEPROP 2 LAST CDS_LIB pure_quanta
J 0
(1050 6150);
DISPLAY INVISIBLE (1050 6150);
FORCEPROP 0 LAST $SEC 1
J 0
(1225 6275);
DISPLAY 0.680851 (1225 6275);
PAINT MONO (1225 6275);
DISPLAY INVISIBLE (1225 6275);
FORCEPROP 2 LAST CDS_SEC 1
J 0
(1225 6275);
DISPLAY 1.021277 (1225 6275);
DISPLAY INVISIBLE (1225 6275);
FORCEADD UNIVERSAL_POWER..1
(-4700 7875);
FORCEPROP 3 LASTPIN (-4700 7825) SIG_NAME P3V3_AUX\g
J 0
(-4690 7835);
DISPLAY 0.659574 (-4690 7835);
PAINT MONO (-4690 7835);
DISPLAY INVISIBLE (-4690 7835);
FORCEPROP 1 LAST HDL_POWER P3V3_AUX
J 1
(-4700 7925);
DISPLAY 0.872340 (-4700 7925);
PAINT GREEN (-4700 7925);
FORCEPROP 1 LAST PATH I46
J 0
(-4650 7900);
DISPLAY 0.872340 (-4650 7900);
PAINT AQUA (-4650 7900);
DISPLAY INVISIBLE (-4650 7900);
FORCEPROP 2 LAST CDS_LIB logical_power
J 0
(-4700 7875);
PAINT MONO (-4700 7875);
DISPLAY INVISIBLE (-4700 7875);
FORCEADD UNIVERSAL_POWER..1
(-4675 6475);
FORCEPROP 3 LASTPIN (-4675 6425) SIG_NAME P3V3_AUX\g
J 0
(-4665 6435);
DISPLAY 0.659574 (-4665 6435);
PAINT MONO (-4665 6435);
DISPLAY INVISIBLE (-4665 6435);
FORCEPROP 1 LAST HDL_POWER P3V3_AUX
J 1
(-4675 6525);
DISPLAY 0.872340 (-4675 6525);
PAINT GREEN (-4675 6525);
FORCEPROP 1 LAST PATH I47
J 0
(-4625 6500);
DISPLAY 0.872340 (-4625 6500);
PAINT AQUA (-4625 6500);
DISPLAY INVISIBLE (-4625 6500);
FORCEPROP 2 LAST CDS_LIB logical_power
J 0
(-4675 6475);
PAINT MONO (-4675 6475);
DISPLAY INVISIBLE (-4675 6475);
FORCEADD UNIVERSAL_POWER..1
(-4625 5125);
FORCEPROP 3 LASTPIN (-4625 5075) SIG_NAME P3V3_AUX\g
J 0
(-4615 5085);
DISPLAY 0.659574 (-4615 5085);
PAINT MONO (-4615 5085);
DISPLAY INVISIBLE (-4615 5085);
FORCEPROP 1 LAST HDL_POWER P3V3_AUX
J 1
(-4625 5175);
DISPLAY 0.872340 (-4625 5175);
PAINT GREEN (-4625 5175);
FORCEPROP 2 LAST CDS_LIB logical_power
J 0
(-4625 5125);
PAINT MONO (-4625 5125);
DISPLAY INVISIBLE (-4625 5125);
FORCEPROP 1 LAST PATH I49
J 0
(-4575 5150);
DISPLAY 0.872340 (-4575 5150);
PAINT AQUA (-4575 5150);
DISPLAY INVISIBLE (-4575 5150);
FORCEADD UNIVERSAL_POWER..1
(-150 8000);
FORCEPROP 3 LASTPIN (-150 7950) SIG_NAME P3V3_AUX\g
J 0
(-140 7960);
DISPLAY 0.659574 (-140 7960);
PAINT MONO (-140 7960);
DISPLAY INVISIBLE (-140 7960);
FORCEPROP 1 LAST HDL_POWER P3V3_AUX
J 1
(-150 8050);
DISPLAY 0.872340 (-150 8050);
PAINT GREEN (-150 8050);
FORCEPROP 2 LAST CDS_LIB logical_power
J 0
(-150 8000);
PAINT MONO (-150 8000);
DISPLAY INVISIBLE (-150 8000);
FORCEPROP 1 LAST PATH I51
J 0
(-100 8025);
DISPLAY 0.872340 (-100 8025);
PAINT AQUA (-100 8025);
DISPLAY INVISIBLE (-100 8025);
FORCEADD UNIVERSAL_POWER..1
(-150 6625);
FORCEPROP 3 LASTPIN (-150 6575) SIG_NAME P3V3_AUX\g
J 0
(-140 6585);
DISPLAY 0.659574 (-140 6585);
PAINT MONO (-140 6585);
DISPLAY INVISIBLE (-140 6585);
FORCEPROP 1 LAST HDL_POWER P3V3_AUX
J 1
(-150 6675);
DISPLAY 0.872340 (-150 6675);
PAINT GREEN (-150 6675);
FORCEPROP 1 LAST PATH I53
J 0
(-100 6650);
DISPLAY 0.872340 (-100 6650);
PAINT AQUA (-100 6650);
DISPLAY INVISIBLE (-100 6650);
FORCEPROP 2 LAST CDS_LIB logical_power
J 0
(-150 6625);
PAINT MONO (-150 6625);
DISPLAY INVISIBLE (-150 6625);
FORCEADD UNIVERSAL_GND..1
(-4675 6950);
FORCEPROP 3 LASTPIN (-4675 7000) SIG_NAME GND\g
J 0
(-4665 7010);
DISPLAY 0.659574 (-4665 7010);
PAINT MONO (-4665 7010);
DISPLAY INVISIBLE (-4665 7010);
FORCEPROP 2 LAST CDS_LIB logical_power
J 0
(-4675 6950);
DISPLAY INVISIBLE (-4675 6950);
FORCEPROP 1 LAST HDL_POWER GND
J 1
(-4650 6875);
DISPLAY 0.872340 (-4650 6875);
PAINT GREEN (-4650 6875);
DISPLAY INVISIBLE (-4650 6875);
FORCEPROP 1 LAST PATH I55
J 0
(-4600 6950);
DISPLAY 0.872340 (-4600 6950);
PAINT AQUA (-4600 6950);
DISPLAY INVISIBLE (-4600 6950);
FORCEADD Q_RES..2
(-4675 7150);
FORCEPROP 1 LAST PART_NUMBER CS41002FB09
J 0
(-4635 7025);
DISPLAY 0.510638 (-4635 7025);
DISPLAY INVISIBLE (-4635 7025);
FORCEPROP 1 LAST VALUE 100K
J 0
(-4630 7225);
DISPLAY 0.510638 (-4630 7225);
FORCEPROP 1 LAST TOLERANCE 1%
J 0
(-4630 7175);
DISPLAY 0.510638 (-4630 7175);
FORCEPROP 1 LAST MATERIAL EMPTY
J 0
(-4635 7075);
DISPLAY 0.510638 (-4635 7075);
PAINT RED (-4635 7075);
FORCEPROP 1 LAST WATTAGE 1/16W
J 0
(-4635 7125);
DISPLAY 0.510638 (-4635 7125);
FORCEPROP 1 LAST PACK_TYPE 0402LF
J 0
(-4635 6975);
DISPLAY 0.510638 (-4635 6975);
FORCEPROP 1 LAST $LOCATION R2831
J 0
(-4630 7275);
DISPLAY 0.978723 (-4630 7275);
FORCEPROP 1 LASTPIN (-4675 7250) $PN 1
J 0
(-4670 7212);
DISPLAY 0.787234 (-4670 7212);
PAINT MONO (-4670 7212);
FORCEPROP 1 LASTPIN (-4675 7050) $PN 2
J 0
(-4670 7060);
DISPLAY 0.787234 (-4670 7060);
PAINT MONO (-4670 7060);
FORCEPROP 2 LAST CDS_LIB pure_quanta
J 0
(-4675 7150);
DISPLAY INVISIBLE (-4675 7150);
FORCEPROP 1 LAST PATH I56
J 0
(-4625 7325);
DISPLAY 0.978723 (-4625 7325);
PAINT WHITE (-4625 7325);
DISPLAY INVISIBLE (-4625 7325);
FORCEPROP 0 LAST CDS_LOCATION R2831
J 0
(-4625 7325);
DISPLAY 1.021277 (-4625 7325);
DISPLAY INVISIBLE (-4625 7325);
FORCEPROP 0 LAST $SEC 1
J 0
(-4625 7325);
DISPLAY 0.680851 (-4625 7325);
PAINT MONO (-4625 7325);
DISPLAY INVISIBLE (-4625 7325);
FORCEPROP 0 LAST CDS_SEC 1
J 0
(-4625 7325);
DISPLAY 1.021277 (-4625 7325);
DISPLAY INVISIBLE (-4625 7325);
FORCEADD UNIVERSAL_GND..1
(-4650 5575);
FORCEPROP 3 LASTPIN (-4650 5625) SIG_NAME GND\g
J 0
(-4640 5635);
DISPLAY 0.659574 (-4640 5635);
PAINT MONO (-4640 5635);
DISPLAY INVISIBLE (-4640 5635);
FORCEPROP 2 LAST CDS_LIB logical_power
J 0
(-4650 5575);
DISPLAY INVISIBLE (-4650 5575);
FORCEPROP 1 LAST HDL_POWER GND
J 1
(-4625 5500);
DISPLAY 0.872340 (-4625 5500);
PAINT GREEN (-4625 5500);
DISPLAY INVISIBLE (-4625 5500);
FORCEPROP 1 LAST PATH I57
J 0
(-4575 5575);
DISPLAY 0.872340 (-4575 5575);
PAINT AQUA (-4575 5575);
DISPLAY INVISIBLE (-4575 5575);
FORCEADD Q_RES..2
(-4650 5750);
FORCEPROP 1 LAST PART_NUMBER CS41002FB09
J 0
(-4610 5625);
DISPLAY 0.510638 (-4610 5625);
DISPLAY INVISIBLE (-4610 5625);
FORCEPROP 1 LAST WATTAGE 1/16W
J 0
(-4610 5725);
DISPLAY 0.510638 (-4610 5725);
FORCEPROP 1 LAST MATERIAL EMPTY
J 0
(-4610 5675);
DISPLAY 0.510638 (-4610 5675);
PAINT RED (-4610 5675);
FORCEPROP 1 LAST PACK_TYPE 0402LF
J 0
(-4610 5575);
DISPLAY 0.510638 (-4610 5575);
FORCEPROP 1 LAST TOLERANCE 1%
J 0
(-4605 5775);
DISPLAY 0.510638 (-4605 5775);
FORCEPROP 1 LAST VALUE 100K
J 0
(-4605 5825);
DISPLAY 0.510638 (-4605 5825);
FORCEPROP 1 LAST $LOCATION R2829
J 0
(-4605 5875);
DISPLAY 0.978723 (-4605 5875);
FORCEPROP 1 LASTPIN (-4650 5850) $PN 1
J 0
(-4645 5812);
DISPLAY 0.787234 (-4645 5812);
PAINT MONO (-4645 5812);
FORCEPROP 1 LASTPIN (-4650 5650) $PN 2
J 0
(-4645 5660);
DISPLAY 0.787234 (-4645 5660);
PAINT MONO (-4645 5660);
FORCEPROP 2 LAST CDS_LIB pure_quanta
J 0
(-4650 5750);
DISPLAY INVISIBLE (-4650 5750);
FORCEPROP 1 LAST PATH I58
J 0
(-4600 5925);
DISPLAY 0.978723 (-4600 5925);
PAINT WHITE (-4600 5925);
DISPLAY INVISIBLE (-4600 5925);
FORCEPROP 0 LAST CDS_LOCATION R2829
J 0
(-4600 5925);
DISPLAY 1.021277 (-4600 5925);
DISPLAY INVISIBLE (-4600 5925);
FORCEPROP 0 LAST $SEC 1
J 0
(-4600 5925);
DISPLAY 0.680851 (-4600 5925);
PAINT MONO (-4600 5925);
DISPLAY INVISIBLE (-4600 5925);
FORCEPROP 0 LAST CDS_SEC 1
J 0
(-4600 5925);
DISPLAY 1.021277 (-4600 5925);
DISPLAY INVISIBLE (-4600 5925);
FORCEADD UNIVERSAL_GND..1
(-4600 4225);
FORCEPROP 3 LASTPIN (-4600 4275) SIG_NAME GND\g
J 0
(-4590 4285);
DISPLAY 0.659574 (-4590 4285);
PAINT MONO (-4590 4285);
DISPLAY INVISIBLE (-4590 4285);
FORCEPROP 1 LAST PATH I59
J 0
(-4525 4225);
DISPLAY 0.872340 (-4525 4225);
PAINT AQUA (-4525 4225);
DISPLAY INVISIBLE (-4525 4225);
FORCEPROP 1 LAST HDL_POWER GND
J 1
(-4575 4150);
DISPLAY 0.872340 (-4575 4150);
PAINT GREEN (-4575 4150);
DISPLAY INVISIBLE (-4575 4150);
FORCEPROP 2 LAST CDS_LIB logical_power
J 0
(-4600 4225);
DISPLAY INVISIBLE (-4600 4225);
FORCEADD OFFPAGE..4
R 2
(-4950 7350);
FORCEPROP 2 LAST $XR0 140 
J 0
(-5232 7350);
DISPLAY 0.638298 (-5232 7350);
PAINT MONO (-5232 7350);
FORCEPROP 2 LAST PATH I6
J 0
(-5125 7400);
DISPLAY 1.021277 (-5125 7400);
DISPLAY INVISIBLE (-5125 7400);
FORCEPROP 1 LAST OFFPAGE TRUE
J 2
(-5275 7225);
DISPLAY 0.872340 (-5275 7225);
PAINT GREEN (-5275 7225);
DISPLAY INVISIBLE (-5275 7225);
FORCEPROP 1 LAST COMMENT_BODY TRUE
J 2
(-4925 7250);
DISPLAY 0.872340 (-4925 7250);
PAINT GREEN (-4925 7250);
DISPLAY INVISIBLE (-4925 7250);
FORCEPROP 2 LAST CDS_LIB standard
J 0
(-4950 7350);
DISPLAY INVISIBLE (-4950 7350);
FORCEADD Q_RES..2
(-4600 4400);
FORCEPROP 1 LAST PART_NUMBER CS41002FB09
J 0
(-4560 4275);
DISPLAY 0.510638 (-4560 4275);
DISPLAY INVISIBLE (-4560 4275);
FORCEPROP 1 LAST PACK_TYPE 0402LF
J 0
(-4560 4225);
DISPLAY 0.510638 (-4560 4225);
FORCEPROP 1 LAST MATERIAL EMPTY
J 0
(-4560 4325);
DISPLAY 0.510638 (-4560 4325);
PAINT RED (-4560 4325);
FORCEPROP 1 LAST WATTAGE 1/16W
J 0
(-4560 4375);
DISPLAY 0.510638 (-4560 4375);
FORCEPROP 1 LAST TOLERANCE 1%
J 0
(-4555 4425);
DISPLAY 0.510638 (-4555 4425);
FORCEPROP 1 LAST VALUE 100K
J 0
(-4555 4475);
DISPLAY 0.510638 (-4555 4475);
FORCEPROP 1 LAST $LOCATION R2833
J 0
(-4555 4525);
DISPLAY 0.978723 (-4555 4525);
FORCEPROP 1 LASTPIN (-4600 4500) $PN 1
J 0
(-4595 4462);
DISPLAY 0.787234 (-4595 4462);
PAINT MONO (-4595 4462);
FORCEPROP 1 LASTPIN (-4600 4300) $PN 2
J 0
(-4595 4310);
DISPLAY 0.787234 (-4595 4310);
PAINT MONO (-4595 4310);
FORCEPROP 2 LAST CDS_LIB pure_quanta
J 0
(-4600 4400);
DISPLAY INVISIBLE (-4600 4400);
FORCEPROP 1 LAST PATH I60
J 0
(-4550 4575);
DISPLAY 0.978723 (-4550 4575);
PAINT WHITE (-4550 4575);
DISPLAY INVISIBLE (-4550 4575);
FORCEPROP 0 LAST CDS_LOCATION R2833
J 0
(-4550 4575);
DISPLAY 1.021277 (-4550 4575);
DISPLAY INVISIBLE (-4550 4575);
FORCEPROP 0 LAST $SEC 1
J 0
(-4550 4575);
DISPLAY 0.680851 (-4550 4575);
PAINT MONO (-4550 4575);
DISPLAY INVISIBLE (-4550 4575);
FORCEPROP 0 LAST CDS_SEC 1
J 0
(-4550 4575);
DISPLAY 1.021277 (-4550 4575);
DISPLAY INVISIBLE (-4550 4575);
FORCEADD UNIVERSAL_GND..1
(-125 7100);
FORCEPROP 3 LASTPIN (-125 7150) SIG_NAME GND\g
J 0
(-115 7160);
DISPLAY 0.659574 (-115 7160);
PAINT MONO (-115 7160);
DISPLAY INVISIBLE (-115 7160);
FORCEPROP 1 LAST PATH I61
J 0
(-50 7100);
DISPLAY 0.872340 (-50 7100);
PAINT AQUA (-50 7100);
DISPLAY INVISIBLE (-50 7100);
FORCEPROP 1 LAST HDL_POWER GND
J 1
(-100 7025);
DISPLAY 0.872340 (-100 7025);
PAINT GREEN (-100 7025);
DISPLAY INVISIBLE (-100 7025);
FORCEPROP 2 LAST CDS_LIB logical_power
J 0
(-125 7100);
DISPLAY INVISIBLE (-125 7100);
FORCEADD Q_RES..2
(-125 7275);
FORCEPROP 1 LAST PART_NUMBER CS41002FB09
J 0
(-85 7150);
DISPLAY 0.510638 (-85 7150);
DISPLAY INVISIBLE (-85 7150);
FORCEPROP 1 LAST MATERIAL CHIP
J 0
(-85 7200);
DISPLAY 0.510638 (-85 7200);
FORCEPROP 1 LAST WATTAGE 1/16W
J 0
(-85 7250);
DISPLAY 0.510638 (-85 7250);
FORCEPROP 1 LAST TOLERANCE 1%
J 0
(-80 7300);
DISPLAY 0.510638 (-80 7300);
FORCEPROP 1 LAST VALUE 100K
J 0
(-80 7350);
DISPLAY 0.510638 (-80 7350);
FORCEPROP 1 LAST PACK_TYPE 0402LF
J 0
(-85 7100);
DISPLAY 0.510638 (-85 7100);
FORCEPROP 1 LAST $LOCATION R2838
J 0
(-80 7400);
DISPLAY 0.978723 (-80 7400);
FORCEPROP 1 LASTPIN (-125 7375) $PN 1
J 0
(-120 7337);
DISPLAY 0.787234 (-120 7337);
PAINT MONO (-120 7337);
FORCEPROP 1 LASTPIN (-125 7175) $PN 2
J 0
(-120 7185);
DISPLAY 0.787234 (-120 7185);
PAINT MONO (-120 7185);
FORCEPROP 2 LAST CDS_LIB pure_quanta
J 0
(-125 7275);
DISPLAY INVISIBLE (-125 7275);
FORCEPROP 1 LAST PATH I62
J 0
(-75 7450);
DISPLAY 0.978723 (-75 7450);
PAINT WHITE (-75 7450);
DISPLAY INVISIBLE (-75 7450);
FORCEPROP 0 LAST CDS_LOCATION R2838
J 0
(-75 7450);
DISPLAY 1.021277 (-75 7450);
DISPLAY INVISIBLE (-75 7450);
FORCEPROP 0 LAST $SEC 1
J 0
(-75 7450);
DISPLAY 0.680851 (-75 7450);
PAINT MONO (-75 7450);
DISPLAY INVISIBLE (-75 7450);
FORCEPROP 0 LAST CDS_SEC 1
J 0
(-75 7450);
DISPLAY 1.021277 (-75 7450);
DISPLAY INVISIBLE (-75 7450);
FORCEADD UNIVERSAL_GND..1
(-125 5700);
FORCEPROP 3 LASTPIN (-125 5750) SIG_NAME GND\g
J 0
(-115 5760);
DISPLAY 0.659574 (-115 5760);
PAINT MONO (-115 5760);
DISPLAY INVISIBLE (-115 5760);
FORCEPROP 1 LAST HDL_POWER GND
J 1
(-100 5625);
DISPLAY 0.872340 (-100 5625);
PAINT GREEN (-100 5625);
DISPLAY INVISIBLE (-100 5625);
FORCEPROP 2 LAST CDS_LIB logical_power
J 0
(-125 5700);
DISPLAY INVISIBLE (-125 5700);
FORCEPROP 1 LAST PATH I63
J 0
(-50 5700);
DISPLAY 0.872340 (-50 5700);
PAINT AQUA (-50 5700);
DISPLAY INVISIBLE (-50 5700);
FORCEADD Q_RES..2
(-4675 6225);
FORCEPROP 1 LAST PART_NUMBER CS41002FB09
J 0
(-4635 6100);
DISPLAY 0.510638 (-4635 6100);
DISPLAY INVISIBLE (-4635 6100);
FORCEPROP 1 LAST PACK_TYPE 0402LF
J 0
(-4635 6050);
DISPLAY 0.510638 (-4635 6050);
FORCEPROP 1 LAST WATTAGE 1/16W
J 0
(-4635 6200);
DISPLAY 0.510638 (-4635 6200);
FORCEPROP 1 LAST TOLERANCE 1%
J 0
(-4630 6250);
DISPLAY 0.510638 (-4630 6250);
FORCEPROP 1 LAST MATERIAL CHIP
J 0
(-4635 6150);
DISPLAY 0.510638 (-4635 6150);
FORCEPROP 1 LAST VALUE 100K
J 0
(-4630 6300);
DISPLAY 0.510638 (-4630 6300);
FORCEPROP 1 LAST $LOCATION R2828
J 0
(-4630 6350);
DISPLAY 0.978723 (-4630 6350);
FORCEPROP 1 LASTPIN (-4675 6325) $PN 1
J 0
(-4670 6287);
DISPLAY 0.787234 (-4670 6287);
PAINT MONO (-4670 6287);
FORCEPROP 1 LASTPIN (-4675 6125) $PN 2
J 0
(-4670 6135);
DISPLAY 0.787234 (-4670 6135);
PAINT MONO (-4670 6135);
FORCEPROP 1 LAST PATH I66
J 0
(-4625 6400);
DISPLAY 0.978723 (-4625 6400);
PAINT WHITE (-4625 6400);
DISPLAY INVISIBLE (-4625 6400);
FORCEPROP 2 LAST CDS_LIB pure_quanta
J 0
(-4675 6225);
DISPLAY INVISIBLE (-4675 6225);
FORCEPROP 0 LAST CDS_LOCATION R2828
J 0
(-4625 6400);
DISPLAY 1.021277 (-4625 6400);
DISPLAY INVISIBLE (-4625 6400);
FORCEPROP 0 LAST $SEC 1
J 0
(-4625 6400);
DISPLAY 0.680851 (-4625 6400);
PAINT MONO (-4625 6400);
DISPLAY INVISIBLE (-4625 6400);
FORCEPROP 0 LAST CDS_SEC 1
J 0
(-4625 6400);
DISPLAY 1.021277 (-4625 6400);
DISPLAY INVISIBLE (-4625 6400);
FORCEADD Q_RES..2
(-4625 4875);
FORCEPROP 1 LAST PART_NUMBER CS41002FB09
J 0
(-4585 4750);
DISPLAY 0.510638 (-4585 4750);
DISPLAY INVISIBLE (-4585 4750);
FORCEPROP 1 LAST MATERIAL CHIP
J 0
(-4585 4800);
DISPLAY 0.510638 (-4585 4800);
FORCEPROP 1 LAST PACK_TYPE 0402LF
J 0
(-4585 4700);
DISPLAY 0.510638 (-4585 4700);
FORCEPROP 1 LAST VALUE 100K
J 0
(-4580 4950);
DISPLAY 0.510638 (-4580 4950);
FORCEPROP 1 LAST TOLERANCE 1%
J 0
(-4580 4900);
DISPLAY 0.510638 (-4580 4900);
FORCEPROP 1 LAST WATTAGE 1/16W
J 0
(-4585 4850);
DISPLAY 0.510638 (-4585 4850);
FORCEPROP 1 LAST $LOCATION R2832
J 0
(-4580 5000);
DISPLAY 0.978723 (-4580 5000);
FORCEPROP 1 LASTPIN (-4625 4975) $PN 1
J 0
(-4620 4937);
DISPLAY 0.787234 (-4620 4937);
PAINT MONO (-4620 4937);
FORCEPROP 1 LASTPIN (-4625 4775) $PN 2
J 0
(-4620 4785);
DISPLAY 0.787234 (-4620 4785);
PAINT MONO (-4620 4785);
FORCEPROP 1 LAST PATH I67
J 0
(-4575 5050);
DISPLAY 0.978723 (-4575 5050);
PAINT WHITE (-4575 5050);
DISPLAY INVISIBLE (-4575 5050);
FORCEPROP 2 LAST CDS_LIB pure_quanta
J 0
(-4625 4875);
DISPLAY INVISIBLE (-4625 4875);
FORCEPROP 0 LAST CDS_LOCATION R2832
J 0
(-4575 5050);
DISPLAY 1.021277 (-4575 5050);
DISPLAY INVISIBLE (-4575 5050);
FORCEPROP 0 LAST $SEC 1
J 0
(-4575 5050);
DISPLAY 0.680851 (-4575 5050);
PAINT MONO (-4575 5050);
DISPLAY INVISIBLE (-4575 5050);
FORCEPROP 0 LAST CDS_SEC 1
J 0
(-4575 5050);
DISPLAY 1.021277 (-4575 5050);
DISPLAY INVISIBLE (-4575 5050);
FORCEADD Q_RES..2
(-4700 7625);
FORCEPROP 1 LAST PART_NUMBER CS41002FB09
J 0
(-4660 7500);
DISPLAY 0.510638 (-4660 7500);
DISPLAY INVISIBLE (-4660 7500);
FORCEPROP 1 LAST PACK_TYPE 0402LF
J 0
(-4660 7450);
DISPLAY 0.510638 (-4660 7450);
FORCEPROP 1 LAST MATERIAL CHIP
J 0
(-4660 7550);
DISPLAY 0.510638 (-4660 7550);
FORCEPROP 1 LAST WATTAGE 1/16W
J 0
(-4660 7600);
DISPLAY 0.510638 (-4660 7600);
FORCEPROP 1 LAST TOLERANCE 1%
J 0
(-4655 7650);
DISPLAY 0.510638 (-4655 7650);
FORCEPROP 1 LAST VALUE 100K
J 0
(-4655 7700);
DISPLAY 0.510638 (-4655 7700);
FORCEPROP 1 LAST $LOCATION R2830
J 0
(-4655 7750);
DISPLAY 0.978723 (-4655 7750);
FORCEPROP 1 LASTPIN (-4700 7725) $PN 1
J 0
(-4695 7687);
DISPLAY 0.787234 (-4695 7687);
PAINT MONO (-4695 7687);
FORCEPROP 1 LASTPIN (-4700 7525) $PN 2
J 0
(-4695 7535);
DISPLAY 0.787234 (-4695 7535);
PAINT MONO (-4695 7535);
FORCEPROP 1 LAST PATH I68
J 0
(-4650 7800);
DISPLAY 0.978723 (-4650 7800);
PAINT WHITE (-4650 7800);
DISPLAY INVISIBLE (-4650 7800);
FORCEPROP 2 LAST CDS_LIB pure_quanta
J 0
(-4700 7625);
DISPLAY INVISIBLE (-4700 7625);
FORCEPROP 0 LAST CDS_LOCATION R2830
J 0
(-4650 7800);
DISPLAY 1.021277 (-4650 7800);
DISPLAY INVISIBLE (-4650 7800);
FORCEPROP 0 LAST $SEC 1
J 0
(-4650 7800);
DISPLAY 0.680851 (-4650 7800);
PAINT MONO (-4650 7800);
DISPLAY INVISIBLE (-4650 7800);
FORCEPROP 0 LAST CDS_SEC 1
J 0
(-4650 7800);
DISPLAY 1.021277 (-4650 7800);
DISPLAY INVISIBLE (-4650 7800);
FORCEADD OFFPAGE..4
R 2
(-4875 5950);
FORCEPROP 2 LAST $XR0 136 
J 0
(-5127 5950);
DISPLAY 0.638298 (-5127 5950);
PAINT MONO (-5127 5950);
FORCEPROP 2 LAST PATH I7
J 0
(-5050 6000);
DISPLAY 1.021277 (-5050 6000);
DISPLAY INVISIBLE (-5050 6000);
FORCEPROP 1 LAST OFFPAGE TRUE
J 2
(-5200 5825);
DISPLAY 0.872340 (-5200 5825);
PAINT GREEN (-5200 5825);
DISPLAY INVISIBLE (-5200 5825);
FORCEPROP 1 LAST COMMENT_BODY TRUE
J 2
(-4850 5850);
DISPLAY 0.872340 (-4850 5850);
PAINT GREEN (-4850 5850);
DISPLAY INVISIBLE (-4850 5850);
FORCEPROP 2 LAST CDS_LIB standard
J 0
(-4875 5950);
DISPLAY INVISIBLE (-4875 5950);
FORCEADD OFFPAGE..4
R 2
(-4875 4600);
FORCEPROP 2 LAST $XR0 136 
J 0
(-5127 4600);
DISPLAY 0.638298 (-5127 4600);
PAINT MONO (-5127 4600);
FORCEPROP 2 LAST CDS_LIB standard
J 0
(-4875 4600);
DISPLAY INVISIBLE (-4875 4600);
FORCEPROP 1 LAST COMMENT_BODY TRUE
J 2
(-4850 4500);
DISPLAY 0.872340 (-4850 4500);
PAINT GREEN (-4850 4500);
DISPLAY INVISIBLE (-4850 4500);
FORCEPROP 1 LAST OFFPAGE TRUE
J 2
(-5200 4475);
DISPLAY 0.872340 (-5200 4475);
PAINT GREEN (-5200 4475);
DISPLAY INVISIBLE (-5200 4475);
FORCEPROP 2 LAST PATH I8
J 0
(-5050 4650);
DISPLAY 1.021277 (-5050 4650);
DISPLAY INVISIBLE (-5050 4650);
FORCEADD Q_RES..2
(-150 7700);
FORCEPROP 1 LAST PART_NUMBER CS41002FB09
J 0
(-110 7575);
DISPLAY 0.510638 (-110 7575);
DISPLAY INVISIBLE (-110 7575);
FORCEPROP 1 LAST PACK_TYPE 0402LF
J 0
(-110 7525);
DISPLAY 0.510638 (-110 7525);
FORCEPROP 1 LAST MATERIAL EMPTY
J 0
(-125 7625);
DISPLAY 0.510638 (-125 7625);
PAINT RED (-125 7625);
FORCEPROP 1 LAST WATTAGE 1/16W
J 0
(-110 7675);
DISPLAY 0.510638 (-110 7675);
FORCEPROP 1 LAST VALUE 100K
J 0
(-105 7775);
DISPLAY 0.510638 (-105 7775);
FORCEPROP 1 LAST TOLERANCE 1%
J 0
(-105 7725);
DISPLAY 0.510638 (-105 7725);
FORCEPROP 1 LAST $LOCATION R2837
J 0
(-105 7825);
DISPLAY 0.978723 (-105 7825);
FORCEPROP 1 LASTPIN (-150 7800) $PN 1
J 0
(-145 7762);
DISPLAY 0.787234 (-145 7762);
PAINT MONO (-145 7762);
FORCEPROP 1 LASTPIN (-150 7600) $PN 2
J 0
(-145 7610);
DISPLAY 0.787234 (-145 7610);
PAINT MONO (-145 7610);
FORCEPROP 1 LAST PATH I80
J 0
(-100 7875);
DISPLAY 0.978723 (-100 7875);
PAINT WHITE (-100 7875);
DISPLAY INVISIBLE (-100 7875);
FORCEPROP 2 LAST CDS_LIB pure_quanta
J 0
(-150 7700);
DISPLAY INVISIBLE (-150 7700);
FORCEPROP 0 LAST CDS_LOCATION R2837
J 0
(-100 7875);
DISPLAY 1.021277 (-100 7875);
DISPLAY INVISIBLE (-100 7875);
FORCEPROP 0 LAST $SEC 1
J 0
(-100 7875);
DISPLAY 0.680851 (-100 7875);
PAINT MONO (-100 7875);
DISPLAY INVISIBLE (-100 7875);
FORCEPROP 0 LAST CDS_SEC 1
J 0
(-100 7875);
DISPLAY 1.021277 (-100 7875);
DISPLAY INVISIBLE (-100 7875);
FORCEADD MOSFET_NCH_DUAL..2
(-2425 7700);
FORCEPROP 1 LAST PART_NUMBER BAM138K0003
J 0
(-2274 7606);
DISPLAY 0.723404 (-2274 7606);
PAINT GREEN (-2274 7606);
DISPLAY INVISIBLE (-2274 7606);
FORCEPROP 2 LAST VALUE PJT138K
J 0
(-2250 7725);
DISPLAY 1.021277 (-2250 7725);
FORCEPROP 2 LAST PART_TYPE SMLF
J 0
(-2250 7775);
DISPLAY 1.021277 (-2250 7775);
FORCEPROP 1 LAST MATERIAL IC
J 0
(-2274 7551);
DISPLAY 0.723404 (-2274 7551);
PAINT GREEN (-2274 7551);
FORCEPROP 1 LAST LOCATION Q67
J 0
(-2274 7676);
DISPLAY 0.723404 (-2274 7676);
PAINT GREEN (-2274 7676);
FORCEPROP 0 LASTPIN (-2375 7900) $PN 3
R 1
J 0
(-2385 7910);
DISPLAY 0.680851 (-2385 7910);
PAINT MONO (-2385 7910);
FORCEPROP 0 LASTPIN (-2625 7650) $PN 5
J 2
(-2635 7660);
DISPLAY 0.680851 (-2635 7660);
PAINT MONO (-2635 7660);
FORCEPROP 0 LASTPIN (-2375 7500) $PN 4
R 1
J 2
(-2385 7490);
DISPLAY 0.680851 (-2385 7490);
PAINT MONO (-2385 7490);
FORCEPROP 1 LAST CDS_LMAN_SYM_OUTLINE -150,150,150,-150
J 0
(-2425 7700);
DISPLAY 0.468085 (-2425 7700);
PAINT GREEN (-2425 7700);
DISPLAY INVISIBLE (-2425 7700);
FORCEPROP 1 LAST PATH I82
J 0
(-2275 7550);
DISPLAY 0.723404 (-2275 7550);
PAINT GREEN (-2275 7550);
DISPLAY INVISIBLE (-2275 7550);
FORCEPROP 1 LAST NEEDS_NO_SIZE TRUE
J 0
(-2275 7591);
DISPLAY 0.468085 (-2275 7591);
PAINT GREEN (-2275 7591);
DISPLAY INVISIBLE (-2275 7591);
FORCEPROP 2 LAST CDS_LIB pure_quanta
J 0
(-2425 7700);
DISPLAY INVISIBLE (-2425 7700);
FORCEPROP 0 LAST $SEC 2
J 0
(-2250 7825);
DISPLAY 0.680851 (-2250 7825);
PAINT MONO (-2250 7825);
DISPLAY INVISIBLE (-2250 7825);
FORCEPROP 0 LAST CDS_SEC 2
J 0
(-2250 7825);
DISPLAY 1.021277 (-2250 7825);
DISPLAY INVISIBLE (-2250 7825);
FORCEADD UNIVERSAL_GND..1
(-2375 7325);
FORCEPROP 3 LASTPIN (-2375 7375) SIG_NAME GND\g
J 0
(-2365 7385);
DISPLAY 0.659574 (-2365 7385);
PAINT MONO (-2365 7385);
DISPLAY INVISIBLE (-2365 7385);
FORCEPROP 2 LAST CDS_LIB logical_power
J 0
(-2375 7325);
DISPLAY INVISIBLE (-2375 7325);
FORCEPROP 1 LAST PATH I83
J 0
(-2300 7325);
DISPLAY 0.872340 (-2300 7325);
PAINT AQUA (-2300 7325);
DISPLAY INVISIBLE (-2300 7325);
FORCEPROP 1 LAST HDL_POWER GND
J 1
(-2350 7250);
DISPLAY 0.872340 (-2350 7250);
PAINT GREEN (-2350 7250);
DISPLAY INVISIBLE (-2350 7250);
FORCEADD Q_RES..2
(-2375 8125);
FORCEPROP 1 LAST PART_NUMBER CS24702JB10
J 0
(-2335 7950);
DISPLAY 0.638298 (-2335 7950);
DISPLAY INVISIBLE (-2335 7950);
FORCEPROP 1 LAST PACK_TYPE 0402LF
J 0
(-2335 8000);
DISPLAY 0.638298 (-2335 8000);
FORCEPROP 1 LAST MATERIAL CHIP
J 0
(-2335 8050);
DISPLAY 0.638298 (-2335 8050);
FORCEPROP 1 LAST WATTAGE 1/16W
J 0
(-2335 8100);
DISPLAY 0.638298 (-2335 8100);
FORCEPROP 1 LAST VALUE 4.7K
J 0
(-2330 8200);
DISPLAY 0.638298 (-2330 8200);
FORCEPROP 1 LAST TOLERANCE 5%
J 0
(-2330 8150);
DISPLAY 0.638298 (-2330 8150);
FORCEPROP 1 LAST $LOCATION R2920
J 0
(-2330 8250);
DISPLAY 0.638298 (-2330 8250);
FORCEPROP 1 LASTPIN (-2375 8225) $PN 1
J 0
(-2370 8187);
DISPLAY 0.787234 (-2370 8187);
FORCEPROP 1 LASTPIN (-2375 8025) $PN 2
J 0
(-2370 8035);
DISPLAY 0.787234 (-2370 8035);
FORCEPROP 1 LAST PATH I84
J 0
(-2325 8300);
DISPLAY 0.978723 (-2325 8300);
PAINT WHITE (-2325 8300);
DISPLAY INVISIBLE (-2325 8300);
FORCEPROP 2 LAST CDS_LIB pure_quanta
J 0
(-2375 8125);
PAINT MONO (-2375 8125);
DISPLAY INVISIBLE (-2375 8125);
FORCEPROP 2 LAST CDS_LOCATION R2920
J 0
(-2325 8350);
DISPLAY 1.021277 (-2325 8350);
DISPLAY INVISIBLE (-2325 8350);
FORCEPROP 2 LAST $SEC 1
J 0
(-2325 8350);
DISPLAY 0.680851 (-2325 8350);
PAINT MONO (-2325 8350);
DISPLAY INVISIBLE (-2325 8350);
FORCEPROP 2 LAST CDS_SEC 1
J 0
(-2325 8350);
DISPLAY 1.021277 (-2325 8350);
DISPLAY INVISIBLE (-2325 8350);
FORCEADD UNIVERSAL_POWER..1
(-2375 8350);
FORCEPROP 3 LASTPIN (-2375 8300) SIG_NAME P3V3_AUX\g
J 0
(-2365 8310);
DISPLAY 0.659574 (-2365 8310);
PAINT MONO (-2365 8310);
DISPLAY INVISIBLE (-2365 8310);
FORCEPROP 1 LAST HDL_POWER P3V3_AUX
J 1
(-2375 8400);
DISPLAY 0.872340 (-2375 8400);
PAINT GREEN (-2375 8400);
FORCEPROP 1 LAST PATH I85
J 0
(-2325 8375);
DISPLAY 0.872340 (-2325 8375);
PAINT AQUA (-2325 8375);
DISPLAY INVISIBLE (-2325 8375);
FORCEPROP 2 LAST CDS_LIB logical_power
J 0
(-2375 8350);
PAINT MONO (-2375 8350);
DISPLAY INVISIBLE (-2375 8350);
FORCEADD OFFPAGE..2
(-1425 7900);
FORCEPROP 2 LAST $XR0 213 
J 0
(-1236 7900);
DISPLAY 0.638298 (-1236 7900);
PAINT MONO (-1236 7900);
FORCEPROP 1 LAST COMMENT_BODY TRUE
J 0
(-1470 7805);
DISPLAY 0.872340 (-1470 7805);
PAINT GREEN (-1470 7805);
DISPLAY INVISIBLE (-1470 7805);
FORCEPROP 1 LAST OFFPAGE TRUE
J 0
(-1100 7775);
DISPLAY 0.872340 (-1100 7775);
PAINT AQUA (-1100 7775);
DISPLAY INVISIBLE (-1100 7775);
FORCEPROP 2 LAST PATH I86
J 0
(-1250 7975);
DISPLAY 1.021277 (-1250 7975);
DISPLAY INVISIBLE (-1250 7975);
FORCEPROP 2 LAST CDS_LIB standard
J 0
(-1425 7900);
DISPLAY INVISIBLE (-1425 7900);
FORCEADD OFFPAGE..2
(-1450 6525);
FORCEPROP 2 LAST $XR0 213 
J 0
(-1261 6525);
DISPLAY 0.638298 (-1261 6525);
PAINT MONO (-1261 6525);
FORCEPROP 2 LAST CDS_LIB standard
J 0
(-1450 6525);
DISPLAY INVISIBLE (-1450 6525);
FORCEPROP 1 LAST OFFPAGE TRUE
J 0
(-1125 6400);
DISPLAY 0.872340 (-1125 6400);
PAINT AQUA (-1125 6400);
DISPLAY INVISIBLE (-1125 6400);
FORCEPROP 1 LAST COMMENT_BODY TRUE
J 0
(-1495 6430);
DISPLAY 0.872340 (-1495 6430);
PAINT GREEN (-1495 6430);
DISPLAY INVISIBLE (-1495 6430);
FORCEPROP 2 LAST PATH I87
J 0
(-1250 6575);
DISPLAY 1.021277 (-1250 6575);
DISPLAY INVISIBLE (-1250 6575);
FORCEADD MOSFET_NCH_DUAL..2
(-2525 6300);
FORCEPROP 1 LAST PART_NUMBER BAM138K0003
J 0
(-2374 6206);
DISPLAY 0.723404 (-2374 6206);
PAINT GREEN (-2374 6206);
DISPLAY INVISIBLE (-2374 6206);
FORCEPROP 2 LAST VALUE PJT138K
J 0
(-2350 6325);
DISPLAY 1.021277 (-2350 6325);
FORCEPROP 2 LAST PART_TYPE SMLF
J 0
(-2350 6375);
DISPLAY 1.021277 (-2350 6375);
FORCEPROP 1 LAST MATERIAL IC
J 0
(-2374 6151);
DISPLAY 0.723404 (-2374 6151);
PAINT GREEN (-2374 6151);
FORCEPROP 1 LAST LOCATION Q69
J 0
(-2374 6276);
DISPLAY 0.723404 (-2374 6276);
PAINT GREEN (-2374 6276);
FORCEPROP 0 LASTPIN (-2475 6500) $PN 3
R 1
J 0
(-2485 6510);
DISPLAY 0.680851 (-2485 6510);
PAINT MONO (-2485 6510);
FORCEPROP 0 LASTPIN (-2725 6250) $PN 5
J 2
(-2735 6260);
DISPLAY 0.680851 (-2735 6260);
PAINT MONO (-2735 6260);
FORCEPROP 0 LASTPIN (-2475 6100) $PN 4
R 1
J 2
(-2485 6090);
DISPLAY 0.680851 (-2485 6090);
PAINT MONO (-2485 6090);
FORCEPROP 1 LAST CDS_LMAN_SYM_OUTLINE -150,150,150,-150
J 0
(-2525 6300);
DISPLAY 0.468085 (-2525 6300);
PAINT GREEN (-2525 6300);
DISPLAY INVISIBLE (-2525 6300);
FORCEPROP 1 LAST PATH I88
J 0
(-2375 6150);
DISPLAY 0.723404 (-2375 6150);
PAINT GREEN (-2375 6150);
DISPLAY INVISIBLE (-2375 6150);
FORCEPROP 1 LAST NEEDS_NO_SIZE TRUE
J 0
(-2375 6191);
DISPLAY 0.468085 (-2375 6191);
PAINT GREEN (-2375 6191);
DISPLAY INVISIBLE (-2375 6191);
FORCEPROP 2 LAST CDS_LIB pure_quanta
J 0
(-2525 6300);
DISPLAY INVISIBLE (-2525 6300);
FORCEPROP 0 LAST $SEC 2
J 0
(-2350 6425);
DISPLAY 0.680851 (-2350 6425);
PAINT MONO (-2350 6425);
DISPLAY INVISIBLE (-2350 6425);
FORCEPROP 0 LAST CDS_SEC 2
J 0
(-2350 6425);
DISPLAY 1.021277 (-2350 6425);
DISPLAY INVISIBLE (-2350 6425);
FORCEADD UNIVERSAL_GND..1
(-2475 5925);
FORCEPROP 3 LASTPIN (-2475 5975) SIG_NAME GND\g
J 0
(-2465 5985);
DISPLAY 0.659574 (-2465 5985);
PAINT MONO (-2465 5985);
DISPLAY INVISIBLE (-2465 5985);
FORCEPROP 2 LAST CDS_LIB logical_power
J 0
(-2475 5925);
DISPLAY INVISIBLE (-2475 5925);
FORCEPROP 1 LAST PATH I89
J 0
(-2400 5925);
DISPLAY 0.872340 (-2400 5925);
PAINT AQUA (-2400 5925);
DISPLAY INVISIBLE (-2400 5925);
FORCEPROP 1 LAST HDL_POWER GND
J 1
(-2450 5850);
DISPLAY 0.872340 (-2450 5850);
PAINT GREEN (-2450 5850);
DISPLAY INVISIBLE (-2450 5850);
FORCEADD UNIVERSAL_POWER..1
(-2475 6950);
FORCEPROP 3 LASTPIN (-2475 6900) SIG_NAME P3V3_AUX\g
J 0
(-2465 6910);
DISPLAY 0.659574 (-2465 6910);
PAINT MONO (-2465 6910);
DISPLAY INVISIBLE (-2465 6910);
FORCEPROP 1 LAST HDL_POWER P3V3_AUX
J 1
(-2475 7000);
DISPLAY 0.872340 (-2475 7000);
PAINT GREEN (-2475 7000);
FORCEPROP 1 LAST PATH I90
J 0
(-2425 6975);
DISPLAY 0.872340 (-2425 6975);
PAINT AQUA (-2425 6975);
DISPLAY INVISIBLE (-2425 6975);
FORCEPROP 2 LAST CDS_LIB logical_power
J 0
(-2475 6950);
PAINT MONO (-2475 6950);
DISPLAY INVISIBLE (-2475 6950);
FORCEADD Q_RES..2
(-2475 6725);
FORCEPROP 1 LAST PART_NUMBER CS24702JB10
J 0
(-2435 6550);
DISPLAY 0.638298 (-2435 6550);
DISPLAY INVISIBLE (-2435 6550);
FORCEPROP 1 LAST WATTAGE 1/16W
J 0
(-2435 6700);
DISPLAY 0.638298 (-2435 6700);
FORCEPROP 1 LAST TOLERANCE 5%
J 0
(-2430 6750);
DISPLAY 0.638298 (-2430 6750);
FORCEPROP 1 LAST MATERIAL CHIP
J 0
(-2435 6650);
DISPLAY 0.638298 (-2435 6650);
FORCEPROP 1 LAST PACK_TYPE 0402LF
J 0
(-2435 6600);
DISPLAY 0.638298 (-2435 6600);
FORCEPROP 1 LAST VALUE 4.7K
J 0
(-2430 6800);
DISPLAY 0.638298 (-2430 6800);
FORCEPROP 1 LAST $LOCATION R2919
J 0
(-2430 6850);
DISPLAY 0.638298 (-2430 6850);
FORCEPROP 1 LASTPIN (-2475 6825) $PN 1
J 0
(-2470 6787);
DISPLAY 0.787234 (-2470 6787);
FORCEPROP 1 LASTPIN (-2475 6625) $PN 2
J 0
(-2470 6635);
DISPLAY 0.787234 (-2470 6635);
FORCEPROP 1 LAST PATH I91
J 0
(-2425 6900);
DISPLAY 0.978723 (-2425 6900);
PAINT WHITE (-2425 6900);
DISPLAY INVISIBLE (-2425 6900);
FORCEPROP 2 LAST CDS_LIB pure_quanta
J 0
(-2475 6725);
PAINT MONO (-2475 6725);
DISPLAY INVISIBLE (-2475 6725);
FORCEPROP 2 LAST CDS_LOCATION R2919
J 0
(-2425 6950);
DISPLAY 1.021277 (-2425 6950);
DISPLAY INVISIBLE (-2425 6950);
FORCEPROP 2 LAST $SEC 1
J 0
(-2425 6950);
DISPLAY 0.680851 (-2425 6950);
PAINT MONO (-2425 6950);
DISPLAY INVISIBLE (-2425 6950);
FORCEPROP 2 LAST CDS_SEC 1
J 0
(-2425 6950);
DISPLAY 1.021277 (-2425 6950);
DISPLAY INVISIBLE (-2425 6950);
FORCEADD Q_CAP..1
(-1600 4925);
FORCEPROP 1 LAST PART_NUMBER TMP_QCH21006JB10
J 0
(-1550 4775);
DISPLAY 0.638298 (-1550 4775);
DISPLAY INVISIBLE (-1550 4775);
FORCEPROP 1 LAST VOLTAGE 50V
J 0
(-1550 4925);
DISPLAY 0.638298 (-1550 4925);
FORCEPROP 1 LAST MATERIAL EMPTY
J 0
(-1550 4825);
DISPLAY 0.638298 (-1550 4825);
PAINT RED (-1550 4825);
FORCEPROP 1 LAST PACK_TYPE 0402
J 0
(-1550 4725);
DISPLAY 0.638298 (-1550 4725);
FORCEPROP 1 LAST TOLERANCE 5%
J 0
(-1550 4875);
DISPLAY 0.638298 (-1550 4875);
FORCEPROP 1 LAST VALUE 1000PF
J 0
(-1550 4975);
DISPLAY 0.638298 (-1550 4975);
FORCEPROP 1 LAST $LOCATION C1754
J 0
(-1550 5025);
DISPLAY 0.638298 (-1550 5025);
FORCEPROP 1 LASTPIN (-1600 5025) $PN 1
J 0
(-1590 5005);
DISPLAY 0.787234 (-1590 5005);
PAINT MONO (-1590 5005);
FORCEPROP 1 LASTPIN (-1600 4825) $PN 2
J 0
(-1590 4805);
DISPLAY 0.787234 (-1590 4805);
PAINT MONO (-1590 4805);
FORCEPROP 2 LAST CDS_LIB pure_quanta
J 0
(-1600 4925);
DISPLAY INVISIBLE (-1600 4925);
FORCEPROP 1 LAST PATH I92
J 0
(-1550 5075);
DISPLAY 0.978723 (-1550 5075);
PAINT WHITE (-1550 5075);
DISPLAY INVISIBLE (-1550 5075);
FORCEPROP 2 LAST CDS_LOCATION C1754
J 0
(-1550 5125);
DISPLAY 1.021277 (-1550 5125);
DISPLAY INVISIBLE (-1550 5125);
FORCEPROP 2 LAST $SEC 1
J 0
(-1550 5125);
DISPLAY 0.680851 (-1550 5125);
PAINT MONO (-1550 5125);
DISPLAY INVISIBLE (-1550 5125);
FORCEPROP 2 LAST CDS_SEC 1
J 0
(-1550 5125);
DISPLAY 1.021277 (-1550 5125);
DISPLAY INVISIBLE (-1550 5125);
FORCEADD UNIVERSAL_GND..1
(-1600 4725);
FORCEPROP 3 LASTPIN (-1600 4775) SIG_NAME GND\g
J 0
(-1590 4785);
DISPLAY 0.659574 (-1590 4785);
PAINT MONO (-1590 4785);
DISPLAY INVISIBLE (-1590 4785);
FORCEPROP 2 LAST CDS_LIB logical_power
J 0
(-1600 4725);
DISPLAY INVISIBLE (-1600 4725);
FORCEPROP 1 LAST HDL_POWER GND
J 1
(-1575 4650);
DISPLAY 0.872340 (-1575 4650);
PAINT GREEN (-1575 4650);
DISPLAY INVISIBLE (-1575 4650);
FORCEPROP 1 LAST PATH I93
J 0
(-1525 4725);
DISPLAY 0.872340 (-1525 4725);
PAINT AQUA (-1525 4725);
DISPLAY INVISIBLE (-1525 4725);
FORCEADD OFFPAGE..2
(-1350 5175);
FORCEPROP 2 LAST $XR0 213 
J 0
(-1161 5175);
DISPLAY 0.638298 (-1161 5175);
PAINT MONO (-1161 5175);
FORCEPROP 2 LAST PATH I94
J 0
(-1150 5225);
DISPLAY 1.021277 (-1150 5225);
DISPLAY INVISIBLE (-1150 5225);
FORCEPROP 2 LAST CDS_LIB standard
J 0
(-1350 5175);
DISPLAY INVISIBLE (-1350 5175);
FORCEPROP 1 LAST OFFPAGE TRUE
J 0
(-1025 5050);
DISPLAY 0.872340 (-1025 5050);
PAINT AQUA (-1025 5050);
DISPLAY INVISIBLE (-1025 5050);
FORCEPROP 1 LAST COMMENT_BODY TRUE
J 0
(-1395 5080);
DISPLAY 0.872340 (-1395 5080);
PAINT GREEN (-1395 5080);
DISPLAY INVISIBLE (-1395 5080);
FORCEADD UNIVERSAL_GND..1
(-2500 4550);
FORCEPROP 3 LASTPIN (-2500 4600) SIG_NAME GND\g
J 0
(-2490 4610);
DISPLAY 0.659574 (-2490 4610);
PAINT MONO (-2490 4610);
DISPLAY INVISIBLE (-2490 4610);
FORCEPROP 2 LAST CDS_LIB logical_power
J 0
(-2500 4550);
DISPLAY INVISIBLE (-2500 4550);
FORCEPROP 1 LAST PATH I96
J 0
(-2425 4550);
DISPLAY 0.872340 (-2425 4550);
PAINT AQUA (-2425 4550);
DISPLAY INVISIBLE (-2425 4550);
FORCEPROP 1 LAST HDL_POWER GND
J 1
(-2475 4475);
DISPLAY 0.872340 (-2475 4475);
PAINT GREEN (-2475 4475);
DISPLAY INVISIBLE (-2475 4475);
FORCEADD Q_RES..2
(-2500 5350);
FORCEPROP 1 LAST PART_NUMBER CS24702JB10
J 0
(-2460 5175);
DISPLAY 0.638298 (-2460 5175);
DISPLAY INVISIBLE (-2460 5175);
FORCEPROP 1 LAST PACK_TYPE 0402LF
J 0
(-2460 5225);
DISPLAY 0.638298 (-2460 5225);
FORCEPROP 1 LAST WATTAGE 1/16W
J 0
(-2460 5325);
DISPLAY 0.638298 (-2460 5325);
FORCEPROP 1 LAST MATERIAL CHIP
J 0
(-2460 5275);
DISPLAY 0.638298 (-2460 5275);
FORCEPROP 1 LAST VALUE 4.7K
J 0
(-2455 5425);
DISPLAY 0.638298 (-2455 5425);
FORCEPROP 1 LAST TOLERANCE 5%
J 0
(-2455 5375);
DISPLAY 0.638298 (-2455 5375);
FORCEPROP 1 LAST $LOCATION R2933
J 0
(-2455 5475);
DISPLAY 0.978723 (-2455 5475);
FORCEPROP 1 LASTPIN (-2500 5450) $PN 1
J 0
(-2495 5412);
DISPLAY 0.787234 (-2495 5412);
PAINT MONO (-2495 5412);
FORCEPROP 1 LASTPIN (-2500 5250) $PN 2
J 0
(-2495 5260);
DISPLAY 0.787234 (-2495 5260);
PAINT MONO (-2495 5260);
FORCEPROP 2 LAST CDS_LIB pure_quanta
J 0
(-2500 5350);
DISPLAY INVISIBLE (-2500 5350);
FORCEPROP 1 LAST PATH I97
J 0
(-2450 5525);
DISPLAY 0.978723 (-2450 5525);
PAINT WHITE (-2450 5525);
DISPLAY INVISIBLE (-2450 5525);
FORCEPROP 0 LAST CDS_LOCATION R2933
J 0
(-2450 5525);
DISPLAY 1.021277 (-2450 5525);
DISPLAY INVISIBLE (-2450 5525);
FORCEPROP 0 LAST $SEC 1
J 0
(-2450 5525);
DISPLAY 0.680851 (-2450 5525);
PAINT MONO (-2450 5525);
DISPLAY INVISIBLE (-2450 5525);
FORCEPROP 0 LAST CDS_SEC 1
J 0
(-2450 5525);
DISPLAY 1.021277 (-2450 5525);
DISPLAY INVISIBLE (-2450 5525);
FORCEADD UNIVERSAL_POWER..1
(-2500 5650);
FORCEPROP 3 LASTPIN (-2500 5600) SIG_NAME P3V3_AUX\g
J 0
(-2490 5610);
DISPLAY 0.659574 (-2490 5610);
PAINT MONO (-2490 5610);
DISPLAY INVISIBLE (-2490 5610);
FORCEPROP 1 LAST HDL_POWER P3V3_AUX
J 1
(-2500 5700);
DISPLAY 0.872340 (-2500 5700);
PAINT GREEN (-2500 5700);
FORCEPROP 2 LAST CDS_LIB logical_power
J 0
(-2500 5650);
DISPLAY INVISIBLE (-2500 5650);
FORCEPROP 1 LAST PATH I98
J 0
(-2450 5675);
DISPLAY 0.872340 (-2450 5675);
PAINT AQUA (-2450 5675);
DISPLAY INVISIBLE (-2450 5675);
FORCEADD OFFPAGE..2
(3075 8025);
FORCEPROP 2 LAST $XR0 213 
J 0
(3264 8025);
DISPLAY 0.638298 (3264 8025);
PAINT MONO (3264 8025);
FORCEPROP 2 LAST PATH I99
J 0
(3275 8075);
DISPLAY 1.021277 (3275 8075);
DISPLAY INVISIBLE (3275 8075);
FORCEPROP 1 LAST COMMENT_BODY TRUE
J 0
(3030 7930);
DISPLAY 0.872340 (3030 7930);
PAINT GREEN (3030 7930);
DISPLAY INVISIBLE (3030 7930);
FORCEPROP 1 LAST OFFPAGE TRUE
J 0
(3400 7900);
DISPLAY 0.872340 (3400 7900);
PAINT AQUA (3400 7900);
DISPLAY INVISIBLE (3400 7900);
FORCEPROP 2 LAST CDS_LIB standard
J 0
(3075 8025);
DISPLAY INVISIBLE (3075 8025);
FORCEADD QUANTA_TITLE_BLOCK_C..1
(3750 2300);
FORCEPROP 0 LAST CDS_CON_LAST_MODIFIED Fri Aug 25 14:02:09 2023
J 0
(1865 2315);
PAINT MONO (1865 2315);
DISPLAY INVISIBLE (1865 2315);
FORCEPROP 1 LAST CUSTOM_TXT_CDS <CON_LAST_MODIFIED>
J 0
(1865 2315);
DISPLAY 0.978723 (1865 2315);
FORCEPROP 2 LAST CUSTOM_TXT_CDS <XR_PAGE_TITLE>
J 0
(-4140 7550);
DISPLAY 0.638298 (-4140 7550);
PAINT PINK (-4140 7550);
DISPLAY INVISIBLE (-4140 7550);
FORCEPROP 2 LAST CUSTOM_TXT_CDS <Q_NUMBER>
J 0
(2347 2403);
DISPLAY 1.212766 (2347 2403);
FORCEPROP 2 LAST CUSTOM_TXT_CDS <Q_REV>
J 0
(3566 2403);
DISPLAY 1.212766 (3566 2403);
FORCEPROP 2 LAST CUSTOM_TXT_CDS <CON_PAGE_NUM> OF <CON_TOTAL_PAGES>
J 0
(3304 2318);
DISPLAY 0.978723 (3304 2318);
FORCEPROP 2 LAST CUSTOM_TXT_CDS <Q_PROJ>
J 0
(1368 2402);
DISPLAY 1.212766 (1368 2402);
FORCEPROP 2 LAST CUSTOM_TXT_CDS <NAME_2>
J 0
(575 2350);
FORCEPROP 2 LAST CUSTOM_TXT_CDS <NAME_1>
J 0
(575 2475);
FORCEPROP 1 LAST Q_TITLE EXAMAX_ISO (4/7)
J 0
(-5525 2350);
DISPLAY 1.957447 (-5525 2350);
PAINT GREEN (-5525 2350);
FORCEPROP 1 LAST Q_DEPT 
J 1
(-13 2349);
DISPLAY 1.957447 (-13 2349);
PAINT GREEN (-13 2349);
FORCEPROP 2 LAST CDS_XR_PAGE_TITLE CR-148 : @S9S_MB_2U_LIB.S9S_MB_2U(SCH_1):PAGE148
J 0
(-4140 7550);
DISPLAY 0.638298 (-4140 7550);
PAINT PINK (-4140 7550);
DISPLAY INVISIBLE (-4140 7550);
FORCEPROP 1 LAST COMMENT_BODY TRUE
J 0
(3762 2287);
DISPLAY 0.978723 (3762 2287);
PAINT GREEN (3762 2287);
DISPLAY INVISIBLE (3762 2287);
FORCEPROP 2 LAST PAGE_BORDER TRUE
J 0
(-4140 7550);
DISPLAY 0.638298 (-4140 7550);
PAINT PINK (-4140 7550);
DISPLAY INVISIBLE (-4140 7550);
FORCEPROP 1 LAST CDS_LMAN_SYM_OUTLINE -9475,6775,100,-125
J 0
(3750 2300);
DISPLAY 0.468085 (3750 2300);
PAINT GREEN (3750 2300);
DISPLAY INVISIBLE (3750 2300);
FORCEPROP 2 LAST CDS_LIB pure_quanta
J 0
(3750 2300);
PAINT MONO (3750 2300);
DISPLAY INVISIBLE (3750 2300);
FORCEADD DNS..2
(-175 3375);
PAINT RED (-175 3375);
FORCEPROP 2 LAST CDS_LIB mstr_misc
J 0
(-175 3375);
DISPLAY INVISIBLE (-175 3375);
FORCEPROP 1 LAST COMMENT_BODY TRUE
J 0
(-175 3375);
DISPLAY INVISIBLE (-175 3375);
FORCEADD DNS..2
(2900 3300);
PAINT RED (2900 3300);
FORCEPROP 1 LAST COMMENT_BODY TRUE
J 0
(2900 3300);
DISPLAY INVISIBLE (2900 3300);
FORCEPROP 2 LAST CDS_LIB mstr_misc
J 0
(2900 3300);
DISPLAY INVISIBLE (2900 3300);
FORCEADD DNS..2
(-1600 3150);
PAINT RED (-1600 3150);
FORCEPROP 2 LAST CDS_LIB mstr_misc
J 0
(-1600 3150);
DISPLAY INVISIBLE (-1600 3150);
FORCEPROP 1 LAST COMMENT_BODY TRUE
J 0
(-1600 3150);
DISPLAY INVISIBLE (-1600 3150);
FORCEADD DNS..2
(2950 4850);
PAINT RED (2950 4850);
FORCEPROP 2 LAST CDS_LIB mstr_misc
J 0
(2950 4850);
DISPLAY INVISIBLE (2950 4850);
FORCEPROP 1 LAST COMMENT_BODY TRUE
J 0
(2950 4850);
DISPLAY INVISIBLE (2950 4850);
FORCEADD DNS..2
(2925 6225);
PAINT RED (2925 6225);
FORCEPROP 1 LAST COMMENT_BODY TRUE
J 0
(2925 6225);
DISPLAY INVISIBLE (2925 6225);
FORCEPROP 2 LAST CDS_LIB mstr_misc
J 0
(2925 6225);
DISPLAY INVISIBLE (2925 6225);
FORCEADD DNS..2
(2875 7750);
PAINT RED (2875 7750);
FORCEPROP 2 LAST CDS_LIB mstr_misc
J 0
(2875 7750);
DISPLAY INVISIBLE (2875 7750);
FORCEPROP 1 LAST COMMENT_BODY TRUE
J 0
(2875 7750);
DISPLAY INVISIBLE (2875 7750);
FORCEADD DNS..2
(-1600 4900);
PAINT RED (-1600 4900);
FORCEPROP 2 LAST CDS_LIB mstr_misc
J 0
(-1600 4900);
DISPLAY INVISIBLE (-1600 4900);
FORCEPROP 1 LAST COMMENT_BODY TRUE
J 0
(-1600 4900);
DISPLAY INVISIBLE (-1600 4900);
FORCEADD DNS..2
(-1650 6250);
PAINT RED (-1650 6250);
FORCEPROP 2 LAST CDS_LIB mstr_misc
J 0
(-1650 6250);
DISPLAY INVISIBLE (-1650 6250);
FORCEPROP 1 LAST COMMENT_BODY TRUE
J 0
(-1650 6250);
DISPLAY INVISIBLE (-1650 6250);
FORCEADD DNS..2
(-1600 7625);
PAINT RED (-1600 7625);
FORCEPROP 1 LAST COMMENT_BODY TRUE
J 0
(-1600 7625);
DISPLAY INVISIBLE (-1600 7625);
FORCEPROP 2 LAST CDS_LIB mstr_misc
J 0
(-1600 7625);
DISPLAY INVISIBLE (-1600 7625);
FORCEADD DNS..2
(-150 6300);
PAINT RED (-150 6300);
FORCEPROP 2 LAST CDS_LIB mstr_misc
J 0
(-150 6300);
DISPLAY INVISIBLE (-150 6300);
FORCEPROP 1 LAST COMMENT_BODY TRUE
J 0
(-150 6300);
DISPLAY INVISIBLE (-150 6300);
FORCEADD DNS..2
(-4675 7125);
PAINT RED (-4675 7125);
FORCEPROP 1 LAST COMMENT_BODY TRUE
J 0
(-4675 7125);
DISPLAY INVISIBLE (-4675 7125);
FORCEPROP 2 LAST CDS_LIB mstr_misc
J 0
(-4675 7125);
DISPLAY INVISIBLE (-4675 7125);
FORCEADD DNS..2
(-4650 5725);
PAINT RED (-4650 5725);
FORCEPROP 2 LAST CDS_LIB mstr_misc
J 0
(-4650 5725);
DISPLAY INVISIBLE (-4650 5725);
FORCEPROP 1 LAST COMMENT_BODY TRUE
J 0
(-4650 5725);
DISPLAY INVISIBLE (-4650 5725);
FORCEADD DNS..2
(-4650 2800);
PAINT RED (-4650 2800);
FORCEPROP 2 LAST CDS_LIB mstr_misc
J 0
(-4650 2800);
DISPLAY INVISIBLE (-4650 2800);
FORCEPROP 1 LAST COMMENT_BODY TRUE
J 0
(-4650 2800);
DISPLAY INVISIBLE (-4650 2800);
FORCEADD DNS..2
(-100 4500);
PAINT RED (-100 4500);
FORCEPROP 2 LAST CDS_LIB mstr_misc
J 0
(-100 4500);
DISPLAY INVISIBLE (-100 4500);
FORCEPROP 1 LAST COMMENT_BODY TRUE
J 0
(-100 4500);
DISPLAY INVISIBLE (-100 4500);
FORCEADD DNS..2
(-4600 4375);
PAINT RED (-4600 4375);
FORCEPROP 1 LAST COMMENT_BODY TRUE
J 0
(-4600 4375);
DISPLAY INVISIBLE (-4600 4375);
FORCEPROP 2 LAST CDS_LIB mstr_misc
J 0
(-4600 4375);
DISPLAY INVISIBLE (-4600 4375);
FORCEADD DNS..2
(-150 7675);
PAINT RED (-150 7675);
FORCEPROP 1 LAST COMMENT_BODY TRUE
J 0
(-150 7675);
DISPLAY INVISIBLE (-150 7675);
FORCEPROP 2 LAST CDS_LIB mstr_misc
J 0
(-150 7675);
DISPLAY INVISIBLE (-150 7675);
WIRE 16 -1 (-150 7950)(-150 7800);
WIRE 16 -1 (1100 8175)(1100 8025);
WIRE 16 -1 (1100 6875)(1100 6725);
WIRE 16 -1 (1925 8425)(1925 8275);
WIRE 16 -1 (-3475 6700)(-3475 6550);
WIRE 16 -1 (-2375 8300)(-2375 8225);
WIRE 16 -1 (-3525 8175)(-3525 8100);
WIRE 16 -1 (-4700 7825)(-4700 7725);
WIRE 16 -1 (1125 5500)(1125 5350);
WIRE 16 -1 (2050 5750)(2050 5600);
WIRE 16 -1 (-125 5200)(-125 5050);
WIRE 16 -1 (-150 6575)(-150 6425);
WIRE 16 -1 (-175 3650)(-175 3500);
WIRE 16 -1 (1075 3950)(1075 3800);
WIRE 16 -1 (2000 4200)(2000 4050);
WIRE 16 -1 (-2500 5600)(-2500 5450);
WIRE 16 -1 (-4675 6425)(-4675 6325);
WIRE 16 -1 (-2475 6900)(-2475 6825);
WIRE 16 -1 (-3450 5350)(-3450 5200);
WIRE 16 -1 (-4625 5075)(-4625 4975);
WIRE 16 -1 (-4675 3500)(-4675 3350);
WIRE 16 -1 (-3425 3800)(-3425 3650);
WIRE 16 -1 (-2500 4050)(-2500 3900);
WIRE 16 -1 (2025 7125)(2025 6975);
WIRE 16 -1 (2900 3225)(2900 3175);
WIRE 16 -1 (2000 3300)(2000 3175);
WIRE 16 -1 (1075 3025)(1075 2900);
WIRE 16 -1 (-3425 2875)(-3425 2750);
WIRE 16 -1 (-2500 3150)(-2500 3025);
WIRE 16 -1 (-1600 3075)(-1600 3025);
WIRE 16 -1 (1125 4575)(1125 4450);
WIRE 16 -1 (2950 4775)(2950 4725);
WIRE 16 -1 (2050 4850)(2050 4725);
WIRE 16 -1 (1100 5950)(1100 5825);
WIRE 16 -1 (2025 6225)(2025 6100);
WIRE 16 -1 (2925 6150)(2925 6100);
WIRE 16 -1 (1100 7325)(1100 7200);
WIRE 16 -1 (1925 7600)(1925 7475);
WIRE 16 -1 (2875 7675)(2875 7625);
WIRE 16 -1 (-3450 4450)(-3450 4325);
WIRE 16 -1 (-2500 4725)(-2500 4600);
WIRE 16 -1 (-1600 4825)(-1600 4775);
WIRE 16 -1 (-3475 5800)(-3475 5675);
WIRE 16 -1 (-2475 6100)(-2475 5975);
WIRE 16 -1 (-1650 6175)(-1650 6125);
WIRE 16 -1 (-1600 7550)(-1600 7500);
WIRE 16 -1 (-2375 7500)(-2375 7375);
WIRE 16 -1 (-3525 7200)(-3525 7075);
WIRE 16 -1 (-4675 7000)(-4675 7050);
WIRE 16 -1 (-4650 5625)(-4650 5650);
WIRE 16 -1 (-4600 4275)(-4600 4300);
WIRE 16 -1 (-4650 2675)(-4650 2725);
WIRE 16 -1 (-150 2825)(-150 2875);
WIRE 16 -1 (-100 4375)(-100 4425);
WIRE 16 -1 (-125 5750)(-125 5800);
WIRE 16 -1 (-125 7150)(-125 7175);
WIRE 16 2175 (-325 8100)(175 8100);
WIRE 16 2175 (175 8100)(175 7025);
WIRE 16 2175 (-325 8100)(-325 7025);
WIRE 16 2175 (-325 7025)(175 7025);
WIRE 16 -1 (-150 7475)(-375 7475);
WIRE 16 -1 (-150 7600)(-150 7475);
WIRE 16 -1 (-125 7375)(-125 7475);
WIRE 16 -1 (-125 7475)(-150 7475);
WIRE 16 -1 (850 7475)(-125 7475);
FORCEPROP 2 LAST SIG_NAME FM_SWB_PWRGD
J 0
(190 7485);
DISPLAY 0.808511 (190 7485);
WIRE 16 -1 (-2375 8025)(-2375 7900);
WIRE 16 -1 (-1600 7900)(-2375 7900);
FORCEPROP 2 LAST SIG_NAME BIC_MONITER_ISO
J 0
(-2310 7910);
DISPLAY 0.808511 (-2310 7910);
WIRE 16 -1 (-1600 7900)(-1600 7750);
WIRE 16 -1 (-1475 7900)(-1600 7900);
WIRE 16 -1 (-2475 6500)(-2475 6525);
WIRE 16 -1 (-2475 6625)(-2475 6525);
WIRE 16 -1 (-1650 6525)(-2475 6525);
FORCEPROP 2 LAST SIG_NAME RST_BMC_FROM_SWB_ISO_N
J 0
(-2385 6535);
DISPLAY 0.808511 (-2385 6535);
WIRE 16 -1 (-1650 6525)(-1650 6375);
WIRE 16 -1 (-1500 6525)(-1650 6525);
WIRE 16 -1 (-150 6100)(-375 6100);
WIRE 16 -1 (-150 6225)(-150 6100);
WIRE 16 -1 (-125 6100)(-150 6100);
WIRE 16 -1 (850 6100)(-125 6100);
FORCEPROP 2 LAST SIG_NAME FM_GPU_PWRGD
J 0
(190 6110);
DISPLAY 0.808511 (190 6110);
WIRE 16 -1 (-125 6000)(-125 6100);
WIRE 16 -1 (-4625 4600)(-4825 4600);
WIRE 16 -1 (-4625 4775)(-4625 4600);
WIRE 16 -1 (-4600 4600)(-4625 4600);
WIRE 16 -1 (-4600 4500)(-4600 4600);
WIRE 16 -1 (-3700 4600)(-4600 4600);
FORCEPROP 2 LAST SIG_NAME FM_SWB_BIC_READY_N
J 0
(-4435 4610);
DISPLAY 0.808511 (-4435 4610);
WIRE 16 -1 (-2500 5125)(-2500 5175);
WIRE 16 -1 (-2500 5250)(-2500 5175);
WIRE 16 -1 (-1600 5175)(-2500 5175);
FORCEPROP 2 LAST SIG_NAME FM_SWB_BIC_READY_ISO_N
J 0
(-2360 5185);
DISPLAY 0.808511 (-2360 5185);
WIRE 16 -1 (-1600 5175)(-1600 5025);
WIRE 16 -1 (-1400 5175)(-1600 5175);
WIRE 16 -1 (-3450 4875)(-3450 4850);
WIRE 16 -1 (-3450 5000)(-3450 4875);
WIRE 16 -1 (-2750 4875)(-3450 4875);
FORCEPROP 2 LAST SIG_NAME FM_SWB_BIC_READY
J 0
(-3410 4885);
DISPLAY 0.808511 (-3410 4885);
WIRE 16 -1 (-4675 3025)(-4900 3025);
WIRE 16 -1 (-4675 3150)(-4675 3025);
WIRE 16 -1 (-4650 3025)(-4675 3025);
WIRE 16 -1 (-3675 3025)(-4650 3025);
FORCEPROP 2 LAST SIG_NAME FM_SMB_1_ALERT_GPU_N
J 0
(-4510 3035);
DISPLAY 0.808511 (-4510 3035);
WIRE 16 -1 (-4650 2925)(-4650 3025);
WIRE 16 -1 (-125 4725)(-350 4725);
WIRE 16 -1 (-125 4850)(-125 4725);
WIRE 16 -1 (-100 4725)(-125 4725);
WIRE 16 -1 (875 4725)(-100 4725);
FORCEPROP 2 LAST SIG_NAME FM_SMB_2_ALERT_GPU_N
J 0
(65 4735);
DISPLAY 0.808511 (65 4735);
WIRE 16 -1 (-100 4625)(-100 4725);
WIRE 16 -1 (-175 3175)(-400 3175);
WIRE 16 -1 (-175 3300)(-175 3175);
WIRE 16 -1 (-150 3175)(-175 3175);
WIRE 16 -1 (825 3175)(-150 3175);
FORCEPROP 2 LAST SIG_NAME GPU_FPGA_READY
J 0
(-10 3185);
DISPLAY 0.808511 (-10 3185);
WIRE 16 -1 (-150 3075)(-150 3175);
WIRE 16 -1 (-2500 3575)(-2500 3550);
WIRE 16 -1 (-2500 3700)(-2500 3575);
WIRE 16 -1 (-1600 3575)(-2500 3575);
FORCEPROP 2 LAST SIG_NAME FM_SMB_1_ALERT_GPU_ISO_N
J 0
(-2410 3585);
DISPLAY 0.808511 (-2410 3585);
WIRE 16 -1 (-1600 3575)(-1600 3275);
WIRE 16 -1 (-1375 3575)(-1600 3575);
WIRE 16 -1 (-4675 5950)(-4825 5950);
WIRE 16 -1 (-4675 6125)(-4675 5950);
WIRE 16 -1 (-4650 5850)(-4650 5950);
WIRE 16 -1 (-4650 5950)(-4675 5950);
WIRE 16 -1 (-3725 5950)(-4650 5950);
FORCEPROP 2 LAST SIG_NAME RST_BMC_FROM_SWB_N
J 0
(-4610 5960);
DISPLAY 0.808511 (-4610 5960);
WIRE 16 -1 (-4700 7350)(-4900 7350);
WIRE 16 -1 (-4700 7525)(-4700 7350);
WIRE 16 -1 (-4675 7350)(-4700 7350);
WIRE 16 -1 (-3775 7350)(-4675 7350);
FORCEPROP 2 LAST SIG_NAME BIC_MONITER
J 0
(-4635 7360);
DISPLAY 0.808511 (-4635 7360);
WIRE 16 -1 (-4675 7250)(-4675 7350);
WIRE 16 -1 (-3475 6250)(-3475 6200);
WIRE 16 -1 (-2725 6250)(-3475 6250);
FORCEPROP 2 LAST SIG_NAME RST_BMC_FROM_SWB
J 0
(-3435 6260);
DISPLAY 0.808511 (-3435 6260);
WIRE 16 -1 (-3475 6350)(-3475 6250);
WIRE 16 -1 (2000 3725)(2000 3700);
WIRE 16 -1 (2000 3850)(2000 3725);
WIRE 16 -1 (2900 3725)(2000 3725);
FORCEPROP 2 LAST SIG_NAME GPU_FPGA_READY_ISO
J 0
(2090 3735);
DISPLAY 0.808511 (2090 3735);
WIRE 16 -1 (2900 3725)(2900 3425);
WIRE 16 -1 (3125 3725)(2900 3725);
WIRE 16 -1 (-3525 7600)(-3525 7650);
WIRE 16 -1 (-2625 7650)(-3525 7650);
FORCEPROP 2 LAST SIG_NAME BIC_MONITER_N
J 0
(-3460 7660);
DISPLAY 0.808511 (-3460 7660);
WIRE 16 -1 (-3525 7900)(-3525 7650);
WIRE 16 -1 (1100 7725)(1100 7750);
WIRE 16 -1 (1675 7750)(1100 7750);
FORCEPROP 2 LAST SIG_NAME FM_SWB_PWRGD_N
J 0
(1115 7760);
DISPLAY 0.808511 (1115 7760);
WIRE 16 -1 (1100 7825)(1100 7750);
WIRE 16 -1 (2875 8025)(2875 7875);
WIRE 16 -1 (3025 8025)(2875 8025);
WIRE 16 -1 (1925 8025)(1925 8000);
WIRE 16 -1 (2875 8025)(1925 8025);
FORCEPROP 2 LAST SIG_NAME FM_SWB_PWRGD_ISO
J 0
(2390 8035);
DISPLAY 0.808511 (2390 8035);
WIRE 16 -1 (1925 8075)(1925 8025);
WIRE 16 -1 (2025 6650)(2025 6625);
WIRE 16 -1 (2025 6775)(2025 6650);
WIRE 16 -1 (2925 6650)(2025 6650);
FORCEPROP 2 LAST SIG_NAME FM_GPU_PWRGD_ISO
J 0
(2115 6660);
DISPLAY 0.808511 (2115 6660);
WIRE 16 -1 (2925 6650)(2925 6350);
WIRE 16 -1 (3150 6650)(2925 6650);
WIRE 16 -1 (2050 5275)(2050 5250);
WIRE 16 -1 (2050 5400)(2050 5275);
WIRE 16 -1 (2950 5275)(2950 4975);
WIRE 16 -1 (2950 5275)(2050 5275);
FORCEPROP 2 LAST SIG_NAME FM_SMB_2_ALERT_GPU_ISO_N
J 0
(2140 5285);
DISPLAY 0.808511 (2140 5285);
WIRE 16 -1 (3175 5275)(2950 5275);
WIRE 16 -1 (1100 6350)(1100 6375);
WIRE 16 -1 (1775 6375)(1100 6375);
FORCEPROP 2 LAST SIG_NAME FM_GPU_PWRGD_N
J 0
(1190 6385);
DISPLAY 0.808511 (1190 6385);
WIRE 16 -1 (1100 6525)(1100 6375);
WIRE 16 -1 (1125 4975)(1125 5000);
WIRE 16 -1 (1125 5150)(1125 5000);
WIRE 16 -1 (1800 5000)(1125 5000);
FORCEPROP 2 LAST SIG_NAME FM_SMB_2_ALERT_GPU
J 0
(1140 5010);
DISPLAY 0.808511 (1140 5010);
WIRE 16 -1 (-3425 3275)(-3425 3300);
WIRE 16 -1 (-2750 3300)(-3425 3300);
FORCEPROP 2 LAST SIG_NAME FM_SMB_1_ALERT_GPU
J 0
(-3410 3310);
DISPLAY 0.808511 (-3410 3310);
WIRE 16 -1 (-3425 3450)(-3425 3300);
WIRE 16 -1 (1075 3425)(1075 3450);
WIRE 16 -1 (1075 3600)(1075 3450);
WIRE 16 -1 (1600 3450)(1075 3450);
FORCEPROP 2 LAST SIG_NAME GPU_FPGA_READY_N
J 0
(1090 3460);
DISPLAY 0.808511 (1090 3460);
WIRE 16 -1 (1750 3450)(1600 3450);
WIRE 16 -1 (1600 3450)(1600 2950);
WIRE 16 -1 (1600 2950)(2050 2950);
DOT 1 (-125 7475);
DOT 1 (-1600 3575);
DOT 1 (-2500 3575);
DOT 1 (-3425 3300);
DOT 1 (-4675 3025);
DOT 1 (1075 3450);
DOT 1 (2000 3725);
DOT 1 (2900 3725);
DOT 1 (-4700 7350);
DOT 1 (-3525 7650);
DOT 1 (-1600 7900);
DOT 1 (-3450 4875);
DOT 1 (2875 8025);
DOT 1 (1925 8025);
DOT 1 (2950 5275);
DOT 1 (2050 5275);
DOT 1 (-150 6100);
DOT 1 (1100 6375);
DOT 1 (2025 6650);
DOT 1 (2925 6650);
DOT 1 (1125 5000);
DOT 1 (-125 4725);
DOT 1 (-1650 6525);
DOT 1 (-4675 5950);
DOT 1 (-3475 6250);
DOT 1 (-2475 6525);
DOT 1 (-150 7475);
DOT 1 (1600 3450);
DOT 1 (1100 7750);
DOT 1 (-175 3175);
DOT 1 (-1600 5175);
DOT 1 (-4675 7350);
DOT 1 (-4650 5950);
DOT 1 (-4650 3025);
DOT 1 (-150 3175);
DOT 1 (-100 4725);
DOT 1 (-125 6100);
DOT 1 (-4600 4600);
DOT 1 (-4625 4600);
DOT 1 (-2500 5175);
FORCENOTE
20210527 MODIFY FOR GT
(-5350 8625) 0;
DISPLAY LEFT (-5350 8625);
DISPLAY 2.510638 (-5350 8625);
PAINT PINK (-5350 8625);
FORCENOTE
20211230 DEPOP R2837,POP R2838
(-950 6925) 0;
DISPLAY LEFT (-950 6925);
DISPLAY 1.276596 (-950 6925);
PAINT PINK (-950 6925);
QUIT
